BODY ORDERED NET LIST - 1  
C1               Q_CAP_C0603-4.7UF,25V,10%,X6S,A 1        P1V2_AUX                
                                  2        GND                     
C2               Q_CAP_C0402-1UF,25V,10%,X6S,CHA 1        P1V2_AUX                
                                  2        GND                     
C3               Q_CAP_C0402-1UF,25V,10%,X6S,CHA 1        P1V2_AUX                
                                  2        GND                     
C4               Q_CAP_C0402-1UF,25V,10%,X6S,CHA 1        P1V2_AUX                
                                  2        GND                     
C5               Q_CAP_C0402-1UF,25V,10%,X6S,CHA 1        P1V2_AUX                
                                  2        GND                     
C6               Q_CAP_0402-0.1UF,25V,10%,X7R,CA 1        P2V5_AUX                
                                  2        GND                     
C7               Q_CAP_0402-0.1UF,25V,10%,X7R,CA 1        P1V2_AUX                
                                  2        GND                     
C8               Q_CAP_0402-0.1UF,25V,10%,X7R,CA 1        P2V5_AUX                
                                  2        GND                     
C9               Q_CAP_0402-100PF,50V,5%,NPO,CHA 1        P1V2_AUX                
                                  2        GND                     
C10              Q_CAP_0402-0.1UF,25V,10%,X7R,CA 1        P0V6_DDR_VREF_AUX       
                                  2        GND                     
C11              Q_CAP_0402-0.1UF,10V,10%,EMPTYA 1        VDDI_U2_EMMC            
                                  2        GND                     
C12              Q_CAP_0402-0.22UF,16V,10%,X7R,A 1        M_BMC_DDR4_MCLK_C       
                                  2        GND                     
C13              Q_CAP_0402-0.1UF,25V,10%,X7R,CA 1        P1V2_AUX                
                                  2        GND                     
C14              Q_CAP_0402-0.1UF,25V,10%,X7R,CA 1        P1V2_AUX                
                                  2        GND                     
C15              Q_CAP_C0402-10UF,6.3V,20%,X6S,A 1        P1V2_AUX                
                                  2        GND                     
C16              Q_CAP_C0402-10UF,6.3V,20%,X6S,A 1        P1V2_AUX                
                                  2        GND                     
C17              Q_CAP_0402-0.1UF,25V,10%,X7R,CA 1        P1V2_AUX                
                                  2        GND                     
C18              Q_CAP_0402-0.1UF,25V,10%,X7R,CA 1        P1V2_AUX                
                                  2        GND                     
C19              Q_CAP_0402-0.1UF,25V,10%,X7R,CA 1        P3V3_AUX                
                                  2        GND                     
C20              Q_CAP_0402-0.1UF,25V,10%,X7R,CA 1        P3V3_AUX                
                                  2        GND                     
C21              Q_CAP_C0402-0.01UF,50V,10%,EMPA 1        P0V6_DDR_VREF_AUX       
                                  2        GND                     
C22              Q_CAP_0402-0.1UF,25V,10%,EMPTYA 1        P0V6_DDR_VREF_AUX       
                                  2        GND                     
C23              Q_CAP_0402-0.1UF,25V,10%,X7R,CA 1        P0V6_DDR_VREF_AUX       
                                  2        GND                     
C24              Q_CAP_0402-0.1UF,25V,10%,X7R,CA 1        P2E_BMC_RX_DP           
                                  2        PCIE_BMC_RX_C_DP        
C25              Q_CAP_0402-0.1UF,25V,10%,X7R,CA 1        P2E_BMC_RX_DN           
                                  2        PCIE_BMC_RX_C_DN        
C26              Q_CAP_0402-0.1UF,25V,10%,X7R,CA 1        DP_BMC_C_TX0_P          
                                  2        DP_BMC_TX0_P            
C27              Q_CAP_0402-0.1UF,25V,10%,X7R,CA 1        DP_BMC_C_TX0_N          
                                  2        DP_BMC_TX0_N            
C28              Q_CAP_0402-0.1UF,25V,10%,X7R,CA 1        DP_BMC_C_TX1_P          
                                  2        DP_BMC_TX1_P            
C29              Q_CAP_0402-0.1UF,25V,10%,X7R,CA 1        DP_BMC_C_TX1_N          
                                  2        DP_BMC_TX1_N            
C30              Q_CAP_C0402-1UF,25V,10%,X6S,CHA 1        P3V3_P2V5_P1V8_RVDD     
                                  2        GND                     
C31              Q_CAP_0402-0.1UF,25V,10%,X7R,CA 1        P3V3_P2V5_P1V8_RVDD     
                                  2        GND                     
C32              Q_CAP_C0402-1UF,25V,10%,X6S,CHA 1        P3V3_P2V5_P1V8_RVDD     
                                  2        GND                     
C33              Q_CAP_0402-0.1UF,25V,10%,X7R,CA 1        P3V3_P2V5_P1V8_RVDD     
                                  2        GND                     
C34              Q_CAP_0402-0.1UF,25V,10%,X7R,CA 1        P3V3_AUX                
                                  2        GND                     
C35              Q_CAP_C0402-1UF,25V,10%,X6S,CHA 1        P3V3_P1V8_SD1VDD        
                                  2        GND                     
C36              Q_CAP_0402-0.1UF,25V,10%,X7R,CA 1        P3V3_P1V8_SD1VDD        
                                  2        GND                     
C37              Q_CAP_0402-0.1UF,25V,10%,X7R,CA 1        P3V3_RGM                
                                  2        GND                     
C38              Q_CAP_C0402-1UF,25V,10%,X6S,CHA 1        P3V3_P1V8_SD2VDD        
                                  2        GND                     
C39              Q_CAP_0402-0.1UF,25V,10%,X7R,CA 1        P3V3_P1V8_SD2VDD        
                                  2        GND                     
C40              Q_CAP_C0402-4.7UF,10V,10%,X5R,A 1        P1V8_BMC_USB2AV18       
                                  2        GND                     
C41              Q_CAP_0402-0.1UF,25V,10%,X7R,CA 1        P1V8_BMC_USB2AV18       
                                  2        GND                     
C42              Q_CAP_C0603-22UF,6.3V,20%,X6S,A 1        PVCCIO_PECI_BMC         
                                  2        GND                     
C43              Q_CAP_C0402-1UF,25V,10%,X6S,CHA 1        PVCCIO_PECI_BMC         
                                  2        GND                     
C44              Q_CAP_C0402-4.7UF,10V,10%,X5R,A 1        P3V3_BMC_USB2AV33       
                                  2        GND                     
C45              Q_CAP_0402-0.1UF,25V,10%,X7R,CA 1        P3V3_BMC_USB2AV33       
                                  2        GND                     
C46              Q_CAP_C0402-1UF,25V,10%,X6S,CHA 1        P1V8_STBY_AVDDPLL       
                                  2        GND                     
C47              Q_CAP_C0402-1UF,25V,10%,X6S,CHA 1        P1V0_STBY_RC_VCC10A     
                                  2        GND                     
C48              Q_CAP_C0402-1UF,25V,10%,X6S,CHA 1        P3V3_STBY_DACAV33       
                                  2        GND                     
C49              Q_CAP_0402-0.1UF,25V,10%,X7R,CA 1        P1V8_STBY_AVDDPLL       
                                  2        GND                     
C50              Q_CAP_0402-0.1UF,25V,10%,X7R,CA 1        P1V0_STBY_RC_VCC10A     
                                  2        GND                     
C51              Q_CAP_0402-0.1UF,25V,10%,X7R,CA 1        P3V3_STBY_DACAV33       
                                  2        GND                     
C52              Q_CAP_C0402-1UF,25V,10%,X6S,CHA 1        P1V0_STBY_PLAVDD        
                                  2        GND                     
C53              Q_CAP_C0402-1UF,25V,10%,X6S,CHA 1        P3V3_P1V8_I2C_I3C       
                                  2        GND                     
C54              Q_CAP_0402-0.1UF,25V,10%,X7R,CA 1        P1V0_STBY_PLAVDD        
                                  2        GND                     
C55              Q_CAP_C0603-22UF,6.3V,20%,X6S,A 1        P1V2_AUX                
                                  2        GND                     
C56              Q_CAP_C0402-1UF,25V,10%,X6S,CHA 1        P1V0_STBY_PLAVDD        
                                  2        GND                     
C57              Q_CAP_0402-0.1UF,25V,10%,X7R,CA 1        P3V3_P1V8_I2C_I3C       
                                  2        GND                     
C58              Q_CAP_C0402-1UF,25V,10%,X6S,CHA 1        P1V2_AUX                
                                  2        GND                     
C59              Q_CAP_0402-0.1UF,25V,10%,X7R,CA 1        P1V0_STBY_PLAVDD        
                                  2        GND                     
C60              Q_CAP_C0402-1UF,25V,10%,X6S,CHA 1        P3V3_STBY_PLLAHVDD      
                                  2        GND                     
C61              Q_CAP_C0402-1UF,25V,10%,X6S,CHA 1        P1V8_STBY_PE_VCC18A     
                                  2        GND                     
C62              Q_CAP_C0402-1UF,25V,10%,X6S,CHA 1        P1V2_AUX                
                                  2        GND                     
C63              Q_CAP_0402-2200PF,50V,10%,X7R,A 1        P1V2_STBY_MVDD_CK       
                                  2        GND                     
C64              Q_CAP_C0402-1UF,25V,10%,X6S,CHA 1        P1V0_STBY_PLAVDD        
                                  2        GND                     
C65              Q_CAP_0402-0.1UF,25V,10%,X7R,CA 1        P3V3_STBY_PLLAHVDD      
                                  2        GND                     
C66              Q_CAP_0402-0.1UF,25V,10%,X7R,CA 1        P1V2_AUX                
                                  2        GND                     
C67              Q_CAP_C0402-1UF,25V,10%,X6S,CHA 1        P1V2_STBY_MVDD_CK       
                                  2        GND                     
C68              Q_CAP_0402-0.1UF,25V,10%,X7R,CA 1        P1V0_STBY_PLAVDD        
                                  2        GND                     
C69              Q_CAP_0402-0.1UF,25V,10%,X7R,CA 1        P1V8_STBY_PE_VCC18A     
                                  2        GND                     
C70              Q_CAP_0402-0.1UF,25V,10%,X7R,CA 1        P1V2_AUX                
                                  2        GND                     
C71              Q_CAP_0402-0.1UF,25V,10%,X7R,CA 1        P1V2_STBY_MVDD_CK       
                                  2        GND                     
C72              Q_CAP_0402-0.1UF,25V,10%,X7R,CA 1        P1V2_AUX                
                                  2        GND                     
C73              Q_CAP_0402-0.1UF,25V,10%,X7R,CA 1        P1V2_STBY_MVDD_CK       
                                  2        GND                     
C74              Q_CAP_0402-0.1UF,25V,10%,X7R,CA 1        P1V2_AUX                
                                  2        GND                     
C75              Q_CAP_C0402-1UF,25V,10%,X6S,CHA 1        A_BMC_ADCAV33           
                                  2        GND                     
C76              Q_CAP_0402-0.1UF,25V,10%,X7R,CA 1        P1V2_AUX                
                                  2        GND                     
C77              Q_CAP_0402-0.1UF,25V,10%,X7R,CA 1        A_BMC_ADCAV33           
                                  2        GND                     
C78              Q_CAP_C0402-1UF,25V,10%,X6S,CHA 1        P1V0_STBY_PE_VCC10A     
                                  2        GND                     
C79              Q_CAP_0402-0.1UF,25V,10%,X7R,CA 1        P1V0_STBY_PE_VCC10A     
                                  2        GND                     
C80              Q_CAP_C0402-1UF,25V,10%,X6S,CHA 1        P1V8_STBY_RC_VCC18A     
                                  2        GND                     
C81              Q_CAP_0402-0.1UF,25V,10%,X7R,CA 1        P1V8_STBY_RC_VCC18A     
                                  2        GND                     
C82              Q_CAP_0402-0.1UF,25V,10%,X7R,CA 1        P1V2_AUX                
                                  2        GND                     
C83              Q_CAP_0402-0.1UF,25V,10%,X7R,CA 1        P3V3_RTC_AUX            
                                  2        GND                     
C84              Q_CAP_0402-0.1UF,25V,10%,X7R,CA 1        P1V2_AUX                
                                  2        GND                     
C85              Q_CAP_0402-0.1UF,25V,10%,X7R,CA 1        P3V3_RGM                
                                  2        GND                     
C86              Q_CAP_0402-0.1UF,25V,10%,X7R,CA 1        P1V0_AUX                
                                  2        GND                     
C87              Q_CAP_0402-0.1UF,25V,10%,X7R,CA 1        P1V8_AUX                
                                  2        GND                     
C88              Q_CAP_0402-0.1UF,25V,10%,X7R,CA 1        P3V3_AUX                
                                  2        GND                     
C89              Q_CAP_0402-0.1UF,25V,10%,X7R,CA 1        P1V8_AUX                
                                  2        GND                     
C90              Q_CAP_C0402-1UF,25V,10%,X6S,CHA 1        P1V0_STBY_DP_VCC10A     
                                  2        GND                     
C91              Q_CAP_0402-0.1UF,25V,10%,X7R,CA 1        P1V2_AUX                
                                  2        GND                     
C92              Q_CAP_0402-0.1UF,25V,10%,X7R,CA 1        P1V0_AUX                
                                  2        GND                     
C93              Q_CAP_0402-0.1UF,25V,10%,X7R,CA 1        P1V8_AUX                
                                  2        GND                     
C94              Q_CAP_0402-0.1UF,25V,10%,X7R,CA 1        P3V3_AUX                
                                  2        GND                     
C95              Q_CAP_0402-0.1UF,25V,10%,X7R,CA 1        P1V8_AUX                
                                  2        GND                     
C96              Q_CAP_0402-0.1UF,25V,10%,X7R,CA 1        PGPPA_BMC_AUX           
                                  2        GND                     
C97              Q_CAP_0402-0.1UF,25V,10%,X7R,CA 1        P1V0_STBY_DP_VCC10A     
                                  2        GND                     
C98              Q_CAP_0402-0.1UF,25V,10%,X7R,CA 1        P1V2_AUX                
                                  2        GND                     
C99              Q_CAP_0402-0.1UF,25V,10%,X7R,CA 1        P1V0_AUX                
                                  2        GND                     
C100             Q_CAP_0402-0.1UF,25V,10%,X7R,CA 1        P1V8_AUX                
                                  2        GND                     
C101             Q_CAP_0402-0.1UF,25V,10%,X7R,CA 1        P3V3_AUX                
                                  2        GND                     
C102             Q_CAP_0402-0.1UF,25V,10%,X7R,CA 1        P1V8_AUX                
                                  2        GND                     
C103             Q_CAP_0402-0.1UF,25V,10%,X7R,CA 1        P1V2_AUX                
                                  2        GND                     
C104             Q_CAP_C0402-1UF,25V,10%,X6S,CHA 1        P1V0_AUX                
                                  2        GND                     
C105             Q_CAP_0402-0.1UF,25V,10%,X7R,CA 1        P1V8_AUX                
                                  2        GND                     
C106             Q_CAP_C0402-1UF,25V,10%,X6S,CHA 1        P1V8_AUX                
                                  2        GND                     
C107             Q_CAP_0402-0.1UF,25V,10%,X7R,CA 1        P1V2_AUX                
                                  2        GND                     
C108             Q_CAP_C0402-1UF,25V,10%,X6S,CHA 1        P1V0_AUX                
                                  2        GND                     
C109             Q_CAP_0402-0.1UF,25V,10%,X7R,CA 1        P1V8_AUX                
                                  2        GND                     
C110             Q_CAP_C0402-1UF,25V,10%,X6S,CHA 1        P3V3_AUX                
                                  2        GND                     
C111             Q_CAP_C0402-1UF,25V,10%,X6S,CHA 1        P1V8_AUX                
                                  2        GND                     
C112             Q_CAP_0402-0.1UF,25V,10%,X7R,CA 1        P1V2_AUX                
                                  2        GND                     
C113             Q_CAP_C0603-22UF,10V,20%,X5R,CA 1        P1V0_AUX                
                                  2        GND                     
C114             Q_CAP_C0402-1UF,25V,10%,X6S,CHA 1        P1V8_AUX                
                                  2        GND                     
C115             Q_CAP_C0402-1UF,25V,10%,X6S,CHA 1        P3V3_AUX                
                                  2        GND                     
C116             Q_CAP_C0402-1UF,25V,10%,X6S,CHA 1        P1V8_AUX                
                                  2        GND                     
C117             Q_CAP_C0402-1UF,25V,10%,X6S,CHA 1        P1V2_AUX                
                                  2        GND                     
C118             Q_CAP_C0603-22UF,6.3V,20%,X6S,A 1        P1V0_AUX                
                                  2        GND                     
C119             Q_CAP_C0402-1UF,25V,10%,X6S,CHA 1        P1V8_AUX                
                                  2        GND                     
C120             Q_CAP_C0603-22UF,10V,20%,X5R,CA 1        P3V3_AUX                
                                  2        GND                     
C121             Q_CAP_C0603-22UF,6.3V,20%,X6S,A 1        P1V8_AUX                
                                  2        GND                     
C122             Q_CAP_C0402-1UF,25V,10%,X6S,CHA 1        P1V2_AUX                
                                  2        GND                     
C123             Q_CAP_C0603-22UF,6.3V,20%,X6S,A 1        P1V0_AUX                
                                  2        GND                     
C124             Q_CAP_C0603-22UF,6.3V,20%,X6S,A 1        P1V8_AUX                
                                  2        GND                     
C125             Q_CAP_C0603-22UF,10V,20%,X5R,CA 1        P3V3_AUX                
                                  2        GND                     
C126             Q_CAP_C0603-22UF,6.3V,20%,X6S,A 1        P1V8_AUX                
                                  2        GND                     
C127             Q_CAP_C0402-1UF,25V,10%,X6S,CHA 1        P1V2_AUX                
                                  2        GND                     
C128             Q_CAP_C0402-1UF,25V,10%,X6S,CHA 1        P1V8_STBY_DP_VCC18A     
                                  2        GND                     
C129             Q_CAP_C0402-1UF,25V,10%,X6S,CHA 1        P1V2_AUX                
                                  2        GND                     
C130             Q_CAP_0402-0.1UF,25V,10%,X7R,CA 1        P1V8_STBY_DP_VCC18A     
                                  2        GND                     
C131             Q_CAP_C0603-22UF,10V,20%,X5R,CA 1        P1V2_AUX                
                                  2        GND                     
C132             Q_CAP_C0603-22UF,10V,20%,X5R,CA 1        P1V2_AUX                
                                  2        GND                     
C133             Q_CAP_C0402-0.01UF,50V,10%,X7RA 1        GND                     
                                  2        A_BMC_ADCVREFN1         
C134             Q_CAP_C0402-0.01UF,50V,10%,X7RA 1        GND                     
                                  2        A_BMC_ADCVREFN0         
C135             Q_CAP_C0402-0.01UF,50V,10%,X7RA 1        GND                     
                                  2        A_BMC_ADCVREFP1         
C136             Q_CAP_C0402-0.01UF,50V,10%,X7RA 1        GND                     
                                  2        A_BMC_ADCVREFP0         
C137             Q_CAP_C0402-0.01UF,50V,10%,X7RA 1        A_BMC_ADCVREFN1         
                                  2        A_BMC_ADCVREFP1         
C138             Q_CAP_C0402-0.01UF,50V,10%,X7RA 1        A_BMC_ADCVREFN0         
                                  2        A_BMC_ADCVREFP0         
C139             Q_CAP_0402-0.1UF,25V,10%,X7R,CA 1        P1V2_P1V0_I3C_VDDL1     
                                  2        GND                     
C140             Q_CAP_0402-0.1UF,25V,10%,X7R,CA 1        P1V2_P1V0_I3C_VDDL2     
                                  2        GND                     
C141             Q_CAP_C0402-12PF,50V,5%,C0G,CHA 1        XTAL_PHY_XI_R           
                                  2        GND                     
C142             Q_CAP_C0402-0.01UF,50V,10%,EMPA 1        GND                     
                                  2        RST_RSTB_N              
C143             Q_CAP_C0402-10UF,10V,20%,X5R,CA 1        P3V3_AUX                
                                  2        GND                     
C144             Q_CAP_0402-0.1UF,25V,10%,X7R,CA 1        P3V3_AUX                
                                  2        GND                     
C145             Q_CAP_C0402-12PF,50V,5%,C0G,CHA 1        XTAL_PHY_XO_R           
                                  2        GND                     
C146             Q_CAP_0402-0.1UF,25V,10%,X7R,CA 1        P3V3_AUX                
                                  2        GND                     
C147             Q_CAP_0402-0.1UF,25V,10%,X7R,CA 1        P3V3_AUX                
                                  2        GND                     
C148             Q_CAP_0402-0.1UF,25V,10%,X7R,CA 1        P3V3_AUX                
                                  2        GND                     
C149             Q_CAP_0402-0.1UF,25V,10%,X7R,CA 1        P3V3_AUX                
                                  2        GND                     
C150             Q_CAP_C0402-0.001UF,50V,10%,X7A 1        PWRGD_P5V_AUX_R         
                                  2        GND                     
C151             Q_CAP_C0402-0.001UF,50V,10%,X7A 1        PWRGD_P3V3_AUX_R        
                                  2        GND                     
C152             Q_CAP_0402-22PF,50V,5%,EMPTY,TA 1        RGMII_BMC_RX_CLK        
                                  2        GND                     
C153             Q_CAP_C0402-0.001UF,50V,10%,X7A 1        PWRGD_P2V5_AUX_R        
                                  2        GND                     
C154             Q_CAP_C0402-0.001UF,50V,10%,X7A 1        PWRGD_P1V8_AUX_R        
                                  2        GND                     
C155             Q_CAP_C0402-0.001UF,50V,10%,X7A 1        PWRGD_P1V2_AUX_R        
                                  2        GND                     
C156             Q_CAP_C0402-0.001UF,50V,10%,X7A 1        PWRGD_P1V0_AUX_R        
                                  2        GND                     
C157             Q_CAP_0402-0.1UF,25V,10%,X7R,CA 1        P3V3_AUX                
                                  2        GND                     
C158             Q_CAP_0402-0.1UF,25V,10%,X7R,CA 1        P3V3_AUX                
                                  2        GND                     
C159             Q_CAP_0402-0.1UF,25V,10%,X7R,CA 1        P3V3_AUX                
                                  2        GND                     
C160             Q_CAP_0402-0.1UF,25V,10%,X7R,CA 1        P3V3_AUX_RJ45           
                                  2        GND                     
C161             Q_CAP_C0402-1UF,25V,10%,X6S,CHA 1        RST_BMC_SELF_HW_D       
                                  2        RST_BMC_SELF_HW_D_C     
C162             Q_CAP_C0603-10UF,16V,20%,X6S,CA 1        P3V3_AUX_RJ45           
                                  2        GND                     
C163             Q_CAP_C0402-0.01UF,50V,10%,X7RA 1        PHY_CT                  
                                  2        GND                     
C164             Q_CAP_C0402-0.01UF,50V,10%,X7RA 1        PHY_CT                  
                                  2        GND                     
C165             Q_CAP_0402-100PF,50V,5%,NPO,CHA 1        PHY_LED3                
                                  2        GND                     
C166             Q_CAP_0402-100PF,50V,5%,NPO,CHA 1        PHY_LED1                
                                  2        GND                     
C167             Q_CAP_0402-100PF,50V,5%,NPO,CHA 1        PHY_LED2                
                                  2        GND                     
C168             Q_CAP_0402-0.1UF,25V,10%,X7R,CA 1        P0V6_DDR_VREF_AUX       
                                  2        GND                     
C169             Q_CAP_C0402-0.01UF,50V,10%,EMPA 1        P1V2_AUX                
                                  2        P0V6_DDR_VREF_AUX       
C170             Q_CAP_C0402-0.01UF,50V,10%,X7RA 1        P0V6_DDR_VREF_AUX       
                                  2        GND                     
C171             Q_CAP_C0805-22UF,16V,20%,X6S,CA 1        P5V_AUX                 
                                  2        GND                     
C172             Q_CAP_0402-470PF,50V,10%,X7R,TA 1        P5V_AUX                 
                                  2        GND                     
C173             Q_CAP_C0402-0.1UF,25V,10%,X6S,A 1        RST_BMC_SELF_HW_D_C     
                                  2        GND                     
C174             Q_CAP_0402-0.1UF,25V,10%,X7R,CA 1        P3V_BAT_R               
                                  2        GND                     
C175             Q_CAP_0402-0.1UF,25V,10%,X7R,CA 1        P3V3_AUX                
                                  2        GND                     
C177             Q_CAP_1206-47UF ,10V,20%,X5R,CA 1        P5V_USB_REAR            
                                  2        GND                     
C178             Q_CAP_0402-470PF,50V,10%,X7R,TA 1        P5V_USB_REAR            
                                  2        GND                     
C179             Q_CAP_0402-470PF,50V,10%,X7R,TA 1        P5V_USB_REAR            
                                  2        GND                     
C180             Q_CAP_C0402-0.1UF,16V,10%,X7R,A 1        P3V3_AUX                
                                  2        GND                     
C181             Q_CAP_0402-1UF,16V,10%,EMPTY,TA 1        LOADSW_CT               
                                  2        GND                     
C182             Q_CAP_C0402-0.1UF,16V,10%,X7R,A 1        P3V3_DP                 
                                  2        GND                     
C183             Q_CAP_C0603-22UF,10V,20%,X5R,CA 1        P3V3_DP_L               
                                  2        GND                     
C184             Q_CAP_C0603-22UF,10V,20%,X5R,CA 1        P3V3_DP_L               
                                  2        GND                     
C185             Q_CAP_0402-0.1UF,25V,10%,X7R,CA 1        DP_BMC_AUX_C_P          
                                  2        DP_BMC_AUX_P            
C186             Q_CAP_0402-0.1UF,25V,10%,X7R,CA 1        DP_BMC_AUX_C_N          
                                  2        DP_BMC_AUX_N            
C187             Q_CAP_0402-0.1UF,25V,10%,X7R,CA 1        P3V3_PL2303             
                                  2        GND                     
C188             Q_CAP_C0603-10UF,16V,20%,X6S,CA 1        P5V_BUS                 
                                  2        GND                     
C189             Q_CAP_0402-0.1UF,25V,10%,X7R,CA 1        P5V_BUS                 
                                  2        GND                     
C190             Q_CAP_C0603-10UF,16V,20%,X6S,CA 1        P5V_BUS                 
                                  2        GND                     
C191             Q_CAP_0402-0.1UF,25V,10%,X7R,CA 1        P3V3_AUX                
                                  2        GND                     
C192             Q_CAP_0402-0.1UF,25V,10%,X7R,CA 1        P3V3_AUX                
                                  2        GND                     
C193             Q_CAP_0402-2.2UF,10V,20%,X5R,TA 1        PVCCA_AUX_PLD           
                                  2        GND                     
C194             Q_CAP_0402-0.1UF,25V,10%,X7R,CA 1        PVCCA_AUX_PLD           
                                  2        GND                     
C195             Q_CAP_0402-0.1UF,25V,10%,X7R,CA 1        PVCCA_AUX_PLD           
                                  2        GND                     
C196             Q_CAP_0402-0.1UF,25V,10%,X7R,CA 1        P3V3_LED                
                                  2        GND                     
C197             Q_CAP_0402-0.1UF,25V,10%,X7R,CA 1        ID_LED_P3V3_AUX         
                                  2        GND                     
C198             Q_CAP_C0402-1UF,25V,10%,X6S,CHA 1        REAR_PWR_BTN_N          
                                  2        GND                     
C199             Q_CAP_C0402-1UF,25V,10%,X6S,CHA 1        REAR_ID_RST_BTN_N       
                                  2        GND                     
C200             Q_CAP_0402-0.1UF,25V,10%,X7R,CA 1        P3V3_AUX                
                                  2        GND                     
C201             Q_CAP_0402-0.1UF,25V,10%,X7R,CA 1        P3V3_AUX                
                                  2        GND                     
C202             Q_CAP_0402-0.1UF,25V,10%,X7R,CA 1        P5V_AUX                 
                                  2        GND                     
C203             Q_CAP_0402-0.1UF,25V,10%,X7R,CA 1        P5V_AUX                 
                                  2        GND                     
C204             Q_CAP_0603-1UF,16V,10%,EMPTY,TA 1        CRT_VCC5                
                                  2        GND                     
C205             Q_CAP_0402-10PF,50V,1%,NPO,TMPA 1        V_DACR                  
                                  2        GND                     
C206             Q_CAP_0402-10PF,50V,1%,NPO,TMPA 1        V_DACG                  
                                  2        GND                     
C207             Q_CAP_0402-10PF,50V,1%,NPO,TMPA 1        V_DACB                  
                                  2        GND                     
C208             Q_CAP_C0402-33PF,50V,1%,C0G,CHA 1        V_DACR_IO               
                                  2        GND                     
C209             Q_CAP_C0402-33PF,50V,1%,C0G,CHA 1        V_DACG_IO               
                                  2        GND                     
C210             Q_CAP_C0402-33PF,50V,1%,C0G,CHA 1        V_DACB_IO               
                                  2        GND                     
C211             Q_CAP_0402-10PF,50V,5%,COG,CH0A 1        V_VGAHS_BUF             
                                  2        GND                     
C212             Q_CAP_0402-10PF,50V,5%,COG,CH0A 1        V_VGAVS_BUF             
                                  2        GND                     
C213             Q_CAP_0402-100PF,50V,5%,EMPTY,A 1        V_BMC_LS_DDC_SDA_R      
                                  2        GND                     
C214             Q_CAP_0402-100PF,50V,5%,EMPTY,A 1        V_BMC_LS_DDC_SCL_R      
                                  2        GND                     
C215             Q_CAP_C0402-10UF,10V,20%,X5R,CA 1        P3V3_AUX                
                                  2        GND                     
C217             Q_CAP_0402-0.1UF,25V,10%,X7R,CA 1        P3V3_AUX                
                                  2        GND                     
C220             Q_CAP_0402-0.1UF,25V,10%,X7R,CA 1        PVCCD_PLL_AUX           
                                  2        GND                     
C221             Q_CAP_0402-0.1UF,25V,10%,X7R,CA 1        P1V2_AUX                
                                  2        GND                     
C222             Q_CAP_0402-0.1UF,25V,10%,X7R,CA 1        P1V2_AUX                
                                  2        GND                     
C223             Q_CAP_C0402-4700P,25V,10%,EMPTA 1        RST_BMC_SRST_BUF_R_N    
                                  2        GND                     
C224             Q_CAP_C0402-10UF,10V,20%,X5R,CA 1        PGPPA_BMC_AUX           
                                  2        GND                     
C225             Q_CAP_0402-0.1UF,25V,10%,X7R,CA 1        P1V2_AUX                
                                  2        GND                     
C226             Q_CAP_0402-0.1UF,10V,10%,EMPTYA 1        P1V8_AUX                
                                  2        GND                     
C227             Q_CAP_0402-0.1UF,10V,10%,EMPTYA 1        P1V8_AUX                
                                  2        GND                     
C228             Q_CAP_0402-0.1UF,10V,10%,EMPTYA 1        P3V3_AUX                
                                  2        GND                     
C229             Q_CAP_0402-0.22UF,16V,10%,EMPTA 1        M_BMC_DDR4_MCLK_C       
                                  2        P1V2_AUX                
C230             Q_CAP_C0402-1UF,25V,10%,EMPTY,A 1        BMC_EMMC_RST_N          
                                  2        GND                     
C231             Q_CAP_C0402-1UF,6.3V,10%,EMPTYA 1        VDDI_U2_EMMC            
                                  2        GND                     
C232             Q_CAP_C0603-22UF,6.3V,20%,EMPTA 1        P1V8_AUX                
                                  2        GND                     
C233             Q_CAP_0402-0.1UF,10V,10%,EMPTYA 1        P1V8_AUX                
                                  2        GND                     
C234             Q_CAP_C0603-22UF,10V,20%,EMPTYA 1        P3V3_AUX                
                                  2        GND                     
C235             Q_CAP_0402-0.1UF,10V,10%,EMPTYA 1        P3V3_AUX                
                                  2        GND                     
C240             Q_CAP_C0402-0.1UF,16V,10%,X7R,A 1        P3V3_AUX                
                                  2        GND                     
C241             Q_CAP_0402-0.1UF,10V,10%,X7R,TA 1        P3V3_AUX                
                                  2        GND                     
C244             Q_CAP_C0402-1UF,25V,10%,X6S,CHA 1        P3V3_AUX                
                                  2        GND                     
C246             Q_CAP_C0402-0.01UF,50V,10%,X7RA 1        P3V3_AUX                
                                  2        GND                     
C248             Q_CAP_C0402-10UF,10V,20%,X5R,CA 1        P3V3_AUX                
                                  2        GND                     
C249             Q_CAP_0402-0.1UF,25V,10%,X7R,CA 1        P3V3_AUX                
                                  2        GND                     
C251             Q_CAP_C0402-0.1UF,16V,10%,X7R,A 1        P3V3_RGM                
                                  2        GND                     
C252             Q_CAP_C0402-0.1UF,16V,10%,EMPTA 1        PWRGD_P3V3_RGM_R        
                                  2        GND                     
C253             Q_CAP_0402-0.1UF,25V,10%,X7R,CA 1        P3V3_AUX                
                                  2        GND                     
C255             Q_CAP_0402-0.1UF,25V,10%,X7R,CA 1        P3V3_AUX                
                                  2        GND                     
C256             Q_CAP_C0402-1UF,25V,10%,X6S,CHA 1        P3V3_AUX                
                                  2        GND                     
C257             Q_CAP_C0402-1UF,25V,10%,X6S,CHA 1        P3V3_AUX                
                                  2        GND                     
C258             Q_CAP_C0402-0.01UF,50V,10%,X7RA 1        P3V3_AUX                
                                  2        GND                     
C259             Q_CAP_C0402-0.01UF,50V,10%,X7RA 1        P3V3_AUX                
                                  2        GND                     
C262             Q_CAP_C0402-10UF,6.3V,20%,X6S,A 1        P3V3_AUX                
                                  2        GND                     
C263             Q_CAP_0402-0.1UF,25V,10%,X7R,CA 1        P3V3_AUX                
                                  2        GND                     
C264             Q_CAP_0402-0.1UF,25V,10%,X7R,CA 1        U43_CT                  
                                  2        GND                     
C265             Q_CAP_0402-0.1UF,10V,10%,X7R,TA 1        P1V2_PHY0_PLLVDD        
                                  2        GND                     
C266             Q_CAP_0402-0.1UF,25V,10%,X7R,CA 1        P3V3_AUX                
                                  2        GND                     
C267             Q_CAP_0402-1UF,16V,10%,EMPTY,TA 1        LPC_ESPI_SEL_R1         
                                  2        GND                     
C268             Q_CAP_0402-1UF,16V,10%,EMPTY,TA 1        LPC_ESPI_SEL_LV5        
                                  2        GND                     
C269             Q_CAP_0402-0.1UF,25V,10%,X7R,CA 1        P3V3_AUX                
                                  2        GND                     
C270             Q_CAP_0402-1UF,16V,10%,EMPTY,TA 1        LPC_ESPI_SEL_N          
                                  2        GND                     
C272             Q_CAP_0402-2.2UF,10V,20%,X5R,TA 1        PVCCD_PLL_AUX           
                                  2        GND                     
C273             Q_CAP_0402-1UF,16V,10%,EMPTY,TA 1        LPC_ESPI_SEL_R          
                                  2        GND                     
C274             Q_CAP_0402-0.1UF,25V,10%,X7R,CA 1        P3V3_AUX                
                                  2        GND                     
C275             Q_CAP_0402-100PF,50V,5%,NPO,CHA 1        P3V_BAT_SENSOR          
                                  2        GND                     
C277             Q_CAP_C0402-1UF,25V,10%,X6S,CHA 1        ADCVREFEXT1             
                                  2        GND                     
C278             Q_CAP_0402-0.1UF,25V,10%,X7R,CA 1        P3V3_AUX                
                                  2        GND                     
C279             Q_CAP_0402-0.1UF,25V,10%,X7R,CA 1        ADCVREFEXT1             
                                  2        GND                     
C281             Q_CAP_0402-0.1UF,25V,10%,X7R,CA 1        PVCCD_PLL_AUX           
                                  2        GND                     
C282             Q_CAP_C0402-1UF,25V,10%,X6S,CHA 1        ADCVREFEXT0             
                                  2        GND                     
C284             Q_CAP_0402-0.1UF,25V,10%,X7R,CA 1        ADCVREFEXT0             
                                  2        GND                     
C287             Q_CAP_0402-0.1UF,25V,10%,X7R,CA 1        PVCCD_PLL_AUX           
                                  2        GND                     
C288             Q_CAP_0402-0.1UF,10V,10%,X7R,TA 1        P3V3_XTALVDD            
                                  2        GND                     
C289             Q_CAP_0402-0.1UF,25V,10%,X7R,CA 1        P3V3_AUX                
                                  2        GND                     
C290             Q_CAP_0402-0.1UF,25V,10%,X7R,CA 1        P12V_SENSOR             
                                  2        GND                     
C293             Q_CAP_0402-0.1UF,10V,10%,X7R,TA 1        P3V3_AVDD               
                                  2        GND                     
C295             Q_CAP_0402-0.1UF,25V,10%,X7R,CA 1        P5V_SENSOR              
                                  2        GND                     
C297             Q_CAP_0402-0.1UF,10V,10%,X7R,TA 1        P1V2_PHY0_AVDDL         
                                  2        GND                     
C298             Q_CAP_0402-0.1UF,25V,10%,X7R,CA 1        P3V3_AUX                
                                  2        GND                     
C299             Q_CAP_0402-0.1UF,25V,10%,X7R,CA 1        P3V3_SENSOR             
                                  2        GND                     
C301             Q_CAP_0402-0.1UF,10V,10%,X7R,TA 1        P3V3_AVDD               
                                  2        GND                     
C302             Q_CAP_0402-0.1UF,25V,10%,X7R,CA 1        P3V3_AUX                
                                  2        GND                     
C303             Q_CAP_0402-0.1UF,25V,10%,X7R,CA 1        P2V5_SENSOR             
                                  2        GND                     
C305             Q_CAP_0402-0.1UF,10V,10%,X7R,TA 1        P1V2_PHY0               
                                  2        GND                     
C306             Q_CAP_0402-0.1UF,25V,10%,X7R,CA 1        P3V3_AUX                
                                  2        GND                     
C307             Q_CAP_0402-0.1UF,25V,10%,X7R,CA 1        P1V8_SENSOR             
                                  2        GND                     
C308             Q_CAP_0402-0.1UF,25V,10%,X7R,CA 1        P3V3_AUX                
                                  2        GND                     
C309             Q_CAP_0402-0.1UF,25V,10%,X7R,CA 1        P1V2_SENSOR             
                                  2        GND                     
C310             Q_CAP_0402-0.1UF,25V,10%,X7R,CA 1        P3V3_AUX                
                                  2        GND                     
C311             Q_CAP_0402-0.1UF,25V,10%,X7R,CA 1        P1V0_SENSOR             
                                  2        GND                     
C312             Q_CAP_0402-0.1UF,25V,10%,X7R,CA 1        P3V3_AUX                
                                  2        GND                     
C313             Q_CAP_0402-0.1UF,25V,10%,X7R,CA 1        P3V3_AUX                
                                  2        GND                     
C314             Q_CAP_0402-0.1UF,25V,10%,X7R,CA 1        PGPPA_BMC_AUX_SENSOR    
                                  2        GND                     
C315             Q_CAP_0402-0.1UF,25V,10%,X7R,CA 1        P3V3_AUX                
                                  2        GND                     
C317             Q_CAP_0402-0.1UF,25V,10%,X7R,CA 1        P3V3_AUX                
                                  2        GND                     
C318             Q_CAP_0402-0.1UF,25V,10%,X7R,CA 1        P3V3_AUX                
                                  2        GND                     
C319             Q_CAP_0402-0.1UF,25V,10%,X7R,CA 1        P3V3_AUX                
                                  2        GND                     
C320             Q_CAP_0402-0.1UF,25V,10%,X7R,CA 1        P3V3_AUX                
                                  2        GND                     
C321             Q_CAP_0402-0.1UF,25V,10%,X7R,CA 1        PWR_LED_P3V3_AUX        
                                  2        GND                     
C323             Q_CAP_0402-0.1UF,25V,10%,X7R,CA 1        P3V3_AUX                
                                  2        GND                     
C324             Q_CAP_0402-470PF,50V,10%,X7R,TA 1        ID_LED_BUF_R            
                                  2        GND                     
C326             Q_CAP_0402-470PF,50V,10%,X7R,TA 1        PWR_LED_BUF_R           
                                  2        GND                     
C327             Q_CAP_1206-47UF ,10V,20%,X5R,CA 1        P5V_USB_REAR            
                                  2        GND                     
C328             Q_CAP_0402-0.1UF,10V,10%,X7R,TA 1        P1V2_PHY0_AVDDL         
                                  2        GND                     
C329             Q_CAP_C0805-22UF,25V,20%,X5R,CA 1        P12V_AUX                
                                  2        GND                     
C330             Q_CAP_C0805-22UF,25V,20%,X5R,CA 1        P12V_AUX                
                                  2        GND                     
C331             Q_CAP_0402-0.1UF,10V,10%,X7R,TA 1        P3V3_AVDD               
                                  2        GND                     
C332             Q_CAP_0402-0.1UF,10V,10%,X7R,TA 1        P1V2_PHY0               
                                  2        GND                     
C333             Q_CAP_0402-0.1UF,10V,10%,X7R,TA 1        P3V3_AUX                
                                  2        GND                     
C334             Q_CAP_0402-0.1UF,10V,10%,X7R,TA 1        P3V3_BIASVDD            
                                  2        GND                     
C339             Q_CAP_0402-0.1UF,25V,10%,X7R,CA 1        PVCCA_AUX_PLD           
                                  2        GND                     
C340             Q_CAP_0402-0.1UF,25V,10%,X7R,CA 1        PVCCA_AUX_PLD           
                                  2        GND                     
C341             Q_CAP_0402-0.1UF,25V,10%,X7R,CA 1        PVCCA_AUX_PLD           
                                  2        GND                     
C342             Q_CAP_0402-0.1UF,25V,10%,X7R,CA 1        PVCCA_AUX_PLD           
                                  2        GND                     
C343             Q_CAP_0402-0.1UF,25V,10%,X7R,CA 1        PVCCA_AUX_PLD           
                                  2        GND                     
C344             Q_CAP_0402-0.1UF,25V,10%,X7R,CA 1        PVCCA_AUX_PLD           
                                  2        GND                     
C345             Q_CAP_0402-0.1UF,25V,10%,X7R,CA 1        PVCCA_AUX_PLD           
                                  2        GND                     
C346             Q_CAP_C0402-22UF,6.3V,20%,X5R,A 1        P1V2_PHY0_PLLVDD        
                                  2        GND                     
C347             Q_CAP_0402-4.7UF,10V,10%,X5R,CA 1        P1V2_PHY0_AVDDL         
                                  2        GND                     
C348             Q_CAP_0402-4.7UF,10V,10%,X5R,CA 1        P3V3_AVDD               
                                  2        GND                     
C349             Q_CAP_C0402-22UF,6.3V,20%,X5R,A 1        P1V2_PHY0               
                                  2        GND                     
C350             Q_CAP_0402-4.7UF,10V,10%,X5R,CA 1        P3V3_AUX                
                                  2        GND                     
D0               Q_LED_SMLF-LED_GREEN,19-213/GVA A        PU_LED_POSTCODE_0_N     
                                  C        LED_POSTCODE_0_N        
D1               Q_LED_SMLF-LED_GREEN,19-213/GVA A        PU_LED_POSTCODE_1_N     
                                  C        LED_POSTCODE_1_N        
D2               Q_LED_SMLF-LED_GREEN,19-213/GVA A        PU_LED_POSTCODE_2_N     
                                  C        LED_POSTCODE_2_N        
D3               Q_LED_SMLF-LED_GREEN,19-213/GVA A        PU_LED_POSTCODE_3_N     
                                  C        LED_POSTCODE_3_N        
D4               Q_LED_SMLF-LED_RED,19-217/R6C-A A        PU_LED_POSTCODE_4_N     
                                  C        LED_POSTCODE_4_N        
D5               Q_LED_SMLF-LED_RED,19-217/R6C-A A        PU_LED_POSTCODE_5_N     
                                  C        LED_POSTCODE_5_N        
D6               Q_LED_SMLF-LED_RED,19-217/R6C-A A        PU_LED_POSTCODE_6_N     
                                  C        LED_POSTCODE_6_N        
D7               Q_LED_SMLF-LED_RED,19-217/R6C-A A        PU_LED_POSTCODE_7_N     
                                  C        LED_POSTCODE_7_N        
D8               Q_LED_SMLF-LED_GREEN,19-213/GVA A        BMC_HEARTBEAT_R_N       
                                  C        BMC_HEARTBEAT_N         
D9               SCHOTTKY_AC-SS0530,SMLF,EMPTY,A A        P5V_AUX                 
                                  C        CRT_VCC5                
D10              BZA462A-BZA462A,SMLF,IC,BCZA46A 1        DP_BMC_AUX_C_N          
                                  2        GND                     
                                  3        DP_BMC_HPD_3V3          
                                  4        DP_BMC_AUX_C_P          
                                  5        GND                     
D11              SCHOTTKY_AC-SS0530,SMLF,IC,BCSA A        P5V_AUX                 
                                  C        CRT_VCC5                
D12              BZA462A-BZA462A,SMLF,IC,BCZA46A 1        CRT_VCC5                
                                  2        GND                     
                                  3        CRT_VCC5                
                                  4        CRT_VCC5                
                                  5        GND                     
                                  6        CRT_VCC5                
D13              PCA9517ADP_SMLF-PCA9517ADP,IC,A 1        P3V3_AUX                
                                  2        SMB_BMC_MM16_R1_SCL     
                                  3        SMB_BMC_MM16_R1_SDA     
                                  4        GND                     
                                  5        DEBUG_PORT_PRSNT_BUF_EN 
                                  6        SMB_DEBUG_AUX_LVC3_USB_R1_SDA
                                  7        SMB_DEBUG_AUX_LVC3_USB_R1_SCL
                                  8        P3V3_AUX                
D14              Q_LED_SMLF-LED_BLUE,12-215/BHCA A        PWR_LED_P3V3_AUX        
                                  C        PWR_LED_BUF_R           
D15              Q_LED_SMLF-LED_BLUE,12-215/BHCA A        ID_LED_P3V3_AUX         
                                  C        ID_LED_BUF_R            
D16              SCHOTTKY_AC-RB161SS-20T2R,SMLFA A        CRT_VCC5                
                                  C        UNNAMED_231_QFUSE_I153_1
D17              Q_DIODE_SMLF-SDMK0340L-7-F,IC,A 1        RST_BMC_SELF_HW_R3      
                                  2        RST_BMC_SELF_HW_D       
FS1              Q_FUSE_SMLF-1.1A/8V,IC,DK110TPA 1        UNNAMED_231_QFUSE_I153_1
                                  2        UNNAMED_231_QFUSE_I153_2
GF1              FCONN168_ME1016810106011-FCONNA A1       SMB_BMC_MM14_R1_SCL     
                                  A2       SMB_BMC_MM14_R1_SDA     
                                  A3       SMB_BMC_MM1_SCL         
                                  A4       SMB_BMC_MM1_SDA         
                                  A5       SMB_BMC_MM2_SCL         
                                  A6       SMB_BMC_MM2_SDA         
                                  A7       SMB_BMC_MM3_SCL         
                                  A8       SMB_BMC_MM3_SDA         
                                  A9       SMB_BMC_MM4_SCL         
                                  A10      SMB_BMC_MM4_SDA         
                                  A11      GND                     
                                  A12      CLK_BMC_GF_DP           
                                  A13      CLK_BMC_GF_DN           
                                  A14      GND                     
                                  A15      PCIE_BMC_TX_DP          
                                  A16      PCIE_BMC_TX_DN          
                                  A17      GND                     
                                  A18      PCIE_BMC_RX_C_DP        
                                  A19      PCIE_BMC_RX_C_DN        
                                  A20      GND                     
                                  A21      SMB_BMC_MM5_SCL         
                                  A22      SMB_BMC_MM5_SDA         
                                  A23      SMB_BMC_MM6_SCL         
                                  A24      SMB_BMC_MM6_SDA         
                                  A25      SMB_BMC_MM7_SCL         
                                  A26      SMB_BMC_MM7_SDA         
                                  A27      SMB_BMC_MM8_SCL         
                                  A28      SMB_BMC_MM8_SDA         
                                  A29      SMB_BMC_MM9_SCL         
                                  A30      SMB_BMC_MM9_SDA         
                                  A31      SMB_BMC_MM10_SCL        
                                  A32      SMB_BMC_MM10_SDA        
                                  A33      GND                     
                                  A34      JTAG_MB_TCK             
                                  A35      JTAG_MB_TMS             
                                  A36      JTAG_MB_TDI             
                                  A37      JTAG_MB_TDO             
                                  A38      SMB_BMC_MM12_SCL        
                                  A39      SMB_BMC_MM12_SDA        
                                  A40      SMB_BMC_MM13_SCL        
                                  A41      SMB_BMC_MM13_SDA        
                                  A42      GND                     
                                  A43      GND                     
                                  A44      PWRGD_PSU_AC_PWROK_R    
                                  A45      FM_MB_STBY_EN           
                                  A46      RST_MB_STBY_N           
                                  A47      SYS_PWRBTN_N            
                                  A48      PWRGD_SYS_PWROK         
                                  A49      FM_DBP_CPU_PREQ_GF_R_N  
                                  A50      FM_DBP_BMC_PRDY_N       
                                  A51      RST_PLTRST_N            
                                  A53      RST_ROT_CPU_N           
                                  A54      FM_INTRUDER_HDR_PCH_N   
                                  A55      FM_BMC_CPU_FBRK_OUT_R_N 
                                  A56      IRQ_SMI_ACTIVE_GF_N     
                                  A57      FM_PRSNT_1_N            
                                  A58      GND                     
                                  A61      GND                     
                                  A64      GND                     
                                  A67      GND                     
                                  A70      GND                     
                                  B1       ESPI_HOST_LPC_BMC_CLK   
                                  B2       ESPI_HOST_LPC_BMC_LFRAME_N
                                  B3       IRQ_BMC_LPC_SERIRQ_ESPI_GF
                                  B4       RST_BMC_LPC_ESPI_N      
                                  B5       ESPI_LPC_LAD0_IO0       
                                  B6       ESPI_LPC_LAD1_IO1       
                                  B7       ESPI_LPC_LAD2_IO2       
                                  B8       ESPI_LPC_LAD3_IO3       
                                  B9       LPC_ESPI_SEL            
                                  B10      GND                     
                                  B11      SPI_SYS_R_CLK           
                                  B12      SPI_SYS_CS0_N           
                                  B13      SPI_SYS_R_MOSI          
                                  B14      SPI_SYS_R_MISO          
                                  B15      SPI_SYS_WP_R_IO2        
                                  B16      SPI_SYS_HOLD_R_IO3      
                                  B17      GND                     
                                  B18      RMII_OCP_RCLKI          
                                  B19      RMII_CSRDV              
                                  B20      RMII_TXEN               
                                  B21      RMII_TXD0               
                                  B22      RMII_TXD1               
                                  B23      RMII_RXER               
                                  B24      RMII_RXD0               
                                  B25      RMII_RXD1               
                                  B26      GND                     
                                  B27      PECI_BMC                
                                  B28      PVCCIO_PECI_BMC         
                                  B29      SGPIO_DO_0              
                                  B30      SGPIO_CLK_0             
                                  B31      SGPIO_DI_0              
                                  B32      SGPIO_LD_0              
                                  B33      GND                     
                                  B34      SGPIO_DO_1              
                                  B35      SGPIO_CLK_1             
                                  B36      SGPIO_DI_1              
                                  B37      SGPIO_LD_1              
                                  B38      GND                     
                                  B39      RST_SGPIO_RESET_N       
                                  B40      IRQ_SGPIO_N             
                                  B41      P3V_BAT_R               
                                  B42      QSPI_2_PLD_CS1_N        
                                  B43      GND                     
                                  B44      QSPI_2_PLD_CLK          
                                  B45      QSPI_2_PLD_CS0_N        
                                  B46      QSPI_2_PLD_IO0          
                                  B47      QSPI_2_PLD_IO1          
                                  B48      QSPI_2_PLD_IO2          
                                  B49      QSPI_2_PLD_IO3          
                                  B50      USB_HOST_BMC_B_DP       
                                  B51      USB_HOST_BMC_B_DN       
                                  B52      GND                     
                                  B53      USB_HOST_BMC_A_DP       
                                  B54      USB_HOST_BMC_A_DN       
                                  B55      GND                     
                                  B56      USB_FPNL_DP             
                                  B57      USB_FPNL_DN             
                                  B58      GND                     
                                  B61      GND                     
                                  B64      GND                     
                                  B67      GND                     
                                  B70      GND                     
                                  OA1      P12V_AUX                
                                  OA2      P12V_AUX                
                                  OA3      GND                     
                                  OA4      GND                     
                                  OA5      I3C1_SPD_SCL            
                                  OA6      I3C1_SPD_SDA            
                                  OA7      I3C2_SPD_SCL            
                                  OA8      I3C2_SPD_SDA            
                                  OA9      I3C3_SPD_SCL            
                                  OA10     I3C3_SPD_SDA            
                                  OA11     I3C4_SPD_SCL            
                                  OA12     I3C4_SPD_SDA            
                                  OA13     GND                     
                                  OA14     FM_VIRTUAL_RESEAT       
                                  OB1      P12V_AUX                
                                  OB2      P12V_AUX                
                                  OB3      FM_PRSNT_0_R_N          
                                  OB4      GND                     
                                  OB5      UART_2_BMC_TXD          
                                  OB6      UART_2_BMC_RXD          
                                  OB7      GND                     
                                  OB10     GND                     
                                  OB12     SPI_TPM_CS_N            
H1               HOLE_TH-EMPTY,HOLE620 1        GND                     
H2               HOLE_TH-EMPTY,HOLE620 1        GND                     
H5               HOLE_TH-EMPTY,HOLE1211 1        GND                     
H6               HOLE_TH-EMPTY,HOLE1101 1        GND                     
H7               HOLE_TH-EMPTY,HOLE1101 1        GND                     
H9               HOLE_TH-EMPTY,HOLE1211 1        GND                     
J1               SCONN14_RS6QU0001-SCONN14_RS6-A G1       GND                     
                                  G2       GND                     
                                  L1       LED2_RXDELAY_1G         
                                  L2       LED1_AD1_100M           
                                  L3       LED3_AD0_ACT            
                                  L4       PU_LED_ACT              
                                  R1       PHY_TRD_0_P             
                                  R2       PHY_TRD_0_N             
                                  R3       PHY_TRD_1_P             
                                  R4       PHY_TRD_1_N             
                                  R5       PHY_CT                  
                                  R6       PHY_CT                  
                                  R7       PHY_TRD_2_P             
                                  R8       PHY_TRD_2_N             
                                  R9       PHY_TRD_3_P             
                                  R10      PHY_TRD_3_N             
J2               CONN9_GSB311131HR-CONN9_GSB311A 1        P5V_USB_REAR            
                                  2        USB2_01_F_DN            
                                  3        USB2_01_F_DP            
                                  4        GND                     
                                  5        SMB_DEBUG_AUX_LVC3_USB_SCL
                                  6        SMB_DEBUG_AUX_LVC3_USB_SDA
                                  7        DEBUG_PORT_PRSNT        
                                  8        DEBUG_PORT_UART_TX      
                                  9        DEBUG_PORT_UART_RX      
                                  G1       GND                     
                                  G2       GND                     
J3               SCONN20_3VM11207D7307H-SCONN20A 1        GND                     
                                  2        DP_BMC_HPD_3V3          
                                  3        DP_BMC_TX0_P            
                                  4        DP_CONFIG1              
                                  5        DP_BMC_TX0_N            
                                  6        DP_CONFIG2              
                                  7        GND                     
                                  8        GND                     
                                  9        DP_BMC_TX1_P            
                                  11       DP_BMC_TX1_N            
                                  13       GND                     
                                  14       GND                     
                                  16       DP_BMC_AUX_C_P          
                                  18       DP_BMC_AUX_C_N          
                                  19       GND                     
                                  20       P3V3_DP_L               
                                  G1       GND                     
                                  G2       GND                     
                                  G3       GND                     
                                  G4       GND                     
J4               SCONN5_2UB2141000111F-SCONN5_2A 1        P5V_AUX_VBUS            
                                  2        USB2_EXT_R_DN           
                                  3        USB2_EXT_R_DP           
                                  4        GND                     
                                  5        GND                     
                                  G1       GND                     
                                  G2       GND                     
                                  G3       GND                     
                                  G4       GND                     
J5               SCONN11_9192031111LF-SCONN11_9A 1        SPI_SYS_R1_CLK          
                                  2        RST_PLTRST_TPM_N        
                                  3        SPI_SYS_R1_MOSI         
                                  4        SPI_SYS_R1_MISO         
                                  5        SPI_TPM_CS_N_R          
                                  6        SMB_TPM_MM15_SDA        
                                  7        P3V3_AUX                
                                  8        FM_TPM_PRSNT_0_N        
                                  9        IRQ_TPM_SPI_R_N         
                                  10       SMB_TPM_MM15_SCL        
                                  11       GND                     
                                  G1       GND                     
                                  G2       GND                     
J6               CONN3_210P9103GBR1-CONN3_210-PA 1        UART_BMC_5_TXD_BUF_R    
                                  2        GND                     
                                  3        UART_BMC_5_RXD_BUF      
J7               CONN7_4400547-CONN7_440054-7,TA 1        P3V3_AUX                
                                  2        JTAG_SCM_CONN_TCK       
                                  3        JTAG_SCM_CONN_TDO       
                                  4        JTAG_SCM_CONN_TMS       
                                  5        JTAG_SCM_CONN_TDI       
                                  6        JTAG_SCM_PLD_R1_JTAGEN  
                                  7        GND                     
J8               SCONN13_502240130C001-SCONN13_A 1        V_DACR_IO               
                                  2        GND                     
                                  3        V_DACG_IO               
                                  4        GND                     
                                  5        V_DACB_IO               
                                  6        GND                     
                                  7        V_VGAVS_BUF             
                                  8        GND                     
                                  9        V_VGAHS_BUF             
                                  10       GND                     
                                  11       V_BMC_LS_DDC_SDA_R      
                                  12       V_BMC_LS_DDC_SCL_R      
                                  13       UNNAMED_231_QFUSE_I153_2
                                  G1       GND                     
                                  G2       GND                     
J9               DELTA_L-DELTA-L,THLF,EMPTY,TP24 1        85_5INCH_TOP_DN         
                                  2        85_5INCH_TOP_DP         
                                  3        GND_P1                  
J10              SCONN11_9192031111LF-SCONN11_9A 1        SPI_BMC_TPM_CLK_R       
                                  2        RST_BMC_EXTRST_R3_N     
                                  3        SPI_BMC_TPM_MOSI_R      
                                  4        SPI_BMC_TPM_MISO_R      
                                  5        SPI_BMC_TPM_CS2_N_R     
                                  6        SMB_BMC_TPM_MM15_SDA    
                                  7        P3V3_AUX                
                                  8        FM_TPM_PRSNT_1_N        
                                  9        IRQ_BMC_TPM_SPI_R_N     
                                  10       SMB_BMC_TPM_MM15_SCL    
                                  11       GND                     
                                  G1       GND                     
                                  G2       GND                     
J11              DELTA_L-DELTA-L,THLF,EMPTY,TP24 1        85_5INCH_IN1_DN         
                                  2        85_5INCH_IN1_DP         
                                  3        GND_P2                  
J12              DELTA_L-DELTA-L,THLF,EMPTY,TP24 1        85_5INCH_TOP_DP         
                                  2        85_5INCH_TOP_DN         
                                  3        GND_P1                  
J16              DELTA_L-DELTA-L,THLF,EMPTY,TP24 1        85_5INCH_IN4_DN         
                                  2        85_5INCH_IN4_DP         
                                  3        GND_P2                  
J17              DELTA_L-DELTA-L,THLF,EMPTY,TP24 1        85_5INCH_BOT_DN         
                                  2        85_5INCH_BOT_DP         
                                  3        GND_P1                  
J19              DELTA_L-DELTA-L,THLF,EMPTY,TP24 1        85_5INCH_IN4_DP         
                                  2        85_5INCH_IN4_DN         
                                  3        GND_P2                  
J20              DELTA_L-DELTA-L,THLF,EMPTY,TP24 1        85_5INCH_BOT_DP         
                                  2        85_5INCH_BOT_DN         
                                  3        GND_P1                  
J22              DELTA_L-DELTA-L,THLF,EMPTY,TP24 1        85_10INCH_TOP_DP        
                                  2        85_10INCH_TOP_DN        
                                  3        GND_P1                  
J23              DELTA_L-DELTA-L,THLF,EMPTY,TP24 1        85_10INCH_IN4_DP        
                                  2        85_10INCH_IN4_DN        
                                  3        GND_P2                  
J24              DELTA_L-DELTA-L,THLF,EMPTY,TP24 1        85_10INCH_BOT_DP        
                                  2        85_10INCH_BOT_DN        
                                  3        GND_P1                  
J25              DELTA_L-DELTA-L,THLF,EMPTY,TP24 1        85_10INCH_TOP_DN        
                                  2        85_10INCH_TOP_DP        
                                  3        GND_P1                  
J26              DELTA_L-DELTA-L,THLF,EMPTY,TP24 1        85_10INCH_IN4_DN        
                                  2        85_10INCH_IN4_DP        
                                  3        GND_P2                  
J27              DELTA_L-DELTA-L,THLF,EMPTY,TP24 1        85_10INCH_BOT_DN        
                                  2        85_10INCH_BOT_DP        
                                  3        GND_P1                  
J28              DELTA_L-DELTA-L,THLF,EMPTY,TP24 1        85_10INCH_IN1_DN        
                                  2        85_10INCH_IN1_DP        
                                  3        GND_P1                  
J29              DELTA_L-DELTA-L,THLF,EMPTY,TP24 1        85_5INCH_IN1_DP         
                                  2        85_5INCH_IN1_DN         
                                  3        GND_P2                  
J30              DELTA_L-DELTA-L,THLF,EMPTY,TP24 1        85_10INCH_IN1_DP        
                                  2        85_10INCH_IN1_DN        
                                  3        GND_P1                  
J40              SCONN16_ACASPI006P06-SCONN16_AA 1        SPI_PCH_IO3_FLASH_R1    
                                  2        P3V3_AUX                
                                  3        RST_SPI_PCH_FLASH_R1_N  
                                  7        SPI_PCH_CS0_FLASH_R1_N  
                                  8        SPI_PCH_IO1_FLASH_R1    
                                  9        SPI_PCH_IO2_FLASH_R1    
                                  10       GND                     
                                  15       SPI_PCH_IO0_FLASH_R1    
                                  16       SPI_PCH_CLK_FLASH_R1    
J121             SCONN16_ACASPI006P06-SCONN16_AA 1        SPI_BMC_IO3_FLASH_R1    
                                  2        P3V3_AUX                
                                  3        RST_SPI_BMC_FLASH_R1_N  
                                  7        SPI_BMC_CS0_FLASH_R1_N  
                                  8        SPI_BMC_IO1_FLASH_R1    
                                  9        SPI_BMC_IO2_FLASH_R1    
                                  10       GND                     
                                  15       SPI_BMC_IO0_FLASH_R1    
                                  16       SPI_BMC_CLK_FLASH_R1    
L1               Q_FUSE_SMLF-0.5A/6V,IC,DK050TPA 1        P3V3_DP                 
                                  2        P3V3_DP_L               
L2               Q_INDUCTOR_SMLF-BLM18PG121SN1DB 1        P1V2_AUX                
                                  2        P3V3_STBY_PLLAHVDD      
L3               Q_INDUCTOR_SMLF-BLM18PG121SN1DA 1        P1V8_AUX                
                                  2        P1V8_BMC_USB2AV18       
L4               Q_INDUCTOR_SMLF-BLM18PG121SN1DA 1        P3V3_AUX                
                                  2        P3V3_BMC_USB2AV33       
L5               Q_INDUCTOR_SMLF-BLM18PG121SN1DA 1        P1V8_AUX                
                                  2        P1V8_STBY_AVDDPLL       
L6               Q_INDUCTOR_SMLF-BLM18PG121SN1DA 1        P1V0_AUX                
                                  2        P1V0_STBY_RC_VCC10A     
L7               Q_INDUCTOR_SMLF-BLM18PG121SN1DA 1        P3V3_AUX                
                                  2        P3V3_STBY_DACAV33       
L8               Q_INDUCTOR_SMLF-BLM18PG121SN1DA 1        P1V0_AUX                
                                  2        P1V0_STBY_PLAVDD        
L9               Q_INDUCTOR_SMLF-BLM18PG121SN1DA 1        P3V3_AUX                
                                  2        P3V3_STBY_PLLAHVDD      
L10              Q_INDUCTOR_SMLF-BLM18PG121SN1DA 1        P1V8_AUX                
                                  2        P1V8_STBY_PE_VCC18A     
L11              Q_INDUCTOR_SMLF-BLM18PG121SN1DA 1        P1V2_AUX                
                                  2        P1V2_STBY_MVDD_CK       
L12              Q_INDUCTOR_SMLF-BLM18PG121SN1DA 1        P3V3_AUX                
                                  2        A_BMC_ADCAV33           
L13              Q_INDUCTOR_SMLF-BLM18PG121SN1DA 1        P1V0_AUX                
                                  2        P1V0_STBY_PE_VCC10A     
L14              Q_INDUCTOR_SMLF-BLM18PG121SN1DA 1        P1V8_AUX                
                                  2        P1V8_STBY_RC_VCC18A     
L15              Q_INDUCTOR_SMLF-BLM18PG121SN1DA 1        P1V0_AUX                
                                  2        P1V0_STBY_DP_VCC10A     
L16              Q_INDUCTOR_SMLF-BLM18PG121SN1DA 1        P1V8_AUX                
                                  2        P1V8_STBY_DP_VCC18A     
L17              Q_INDUCTOR_SMLF-BLM18EG121SN1DA 1        PGPPA_BMC_AUX_L         
                                  2        PGPPA_BMC_AUX           
L18              Q_INDUCTOR_SMLF-BLM15PX121SN1DA 1        P3V3_XTALVDD            
                                  2        P3V3_AUX                
L20              Q_INDUCTOR_SMLF-220/1500MA,INDA 1        P3V3_AUX_RJ45           
                                  2        P3V3_AUX                
L23              Q_INDUCTOR4P_12-67/320MA,320MAB 1        USB_FPNL_DP             
                                  2        USB2_01_F_DP            
                                  3        USB2_01_F_DN            
                                  4        USB_FPNL_DN             
L24              Q_INDUCTOR4P_12-67/320MA,320MAA 1        USB2_EXT_DP             
                                  2        USB2_EXT_R_DP           
                                  3        USB2_EXT_R_DN           
                                  4        USB2_EXT_DN             
L26              Q_INDUCTOR_SMLF-BLM18EG121SN1DA 1        P3V3_AUX                
                                  2        PVCCD_PLL_AUX           
L27              Q_INDUCTOR_SMLF-BLM18EG121SN1DA 1        P3V3_AUX                
                                  2        PVCCA_AUX_PLD           
L28              Q_INDUCTOR_SMLF-47/300MA,IND,CA 1        V_DACB                  
                                  2        V_DACB_IO               
L29              Q_INDUCTOR_SMLF-47/300MA,IND,CA 1        V_DACG                  
                                  2        V_DACG_IO               
L30              Q_INDUCTOR_SMLF-47/300MA,IND,CA 1        V_DACR                  
                                  2        V_DACR_IO               
L31              Q_INDUCTOR_SMLF-BLM15PX121SN1DA 1        P3V3_BIASVDD            
                                  2        P3V3_AUX                
L32              Q_INDUCTOR_SMLF-BLM15PX121SN1DA 1        P1V2_PHY0_AVDDL         
                                  2        P1V2_PHY0               
L33              Q_INDUCTOR_SMLF-BLM15PX121SN1DA 1        P1V2_PHY0_PLLVDD        
                                  2        P1V2_PHY0               
L34              Q_INDUCTOR_SMLF-BLM15PX121SN1DA 1        P3V3_AVDD               
                                  2        P3V3_AUX                
OSC1             OSC4_7X25000018-25MHZ,SMLF,MISA 1        PU_25M_BMC_CLK_EN       
                                  2        GND                     
                                  3        BMC_CLK_25M_R           
                                  4        P3V3_RGM                
OSC2             OSC4_7X25000018-25MHZ,SMLF,MISA 1        PU_25M_FPGA_CLK_EN      
                                  2        GND                     
                                  3        CLK_25M_OSC_FPGA_R      
                                  4        P3V3_AUX                
PC205            Q_CAP_0402-0.1UF,25V,10%,X7R,CA 1        EN_P5V_AUX              
                                  2        GND                     
PC206            Q_CAP_C0805-10UF,25V,10%,X6S,CA 1        SW_P5V_AUX_FLT          
                                  2        GND                     
PC207            Q_CAP_C0805-10UF,25V,10%,X6S,CA 1        SW_P5V_AUX_FLT          
                                  2        GND                     
PC208            Q_CAP_C0402-1UF,25V,10%,X6S,CHA 1        P5V_AUX_VCC             
                                  2        GND                     
PC210            Q_CAP_0402-0.1UF,25V,10%,X7R,CA 1        SW_P5V_AUX_FLT          
                                  2        GND                     
PC212            Q_CAP_0402-0.1UF,25V,10%,X7R,CA 1        P5V_AUX                 
                                  2        GND                     
PC213            Q_CAP_C0805-22UF,16V,20%,X6S,CA 1        P5V_AUX                 
                                  2        GND                     
PC214            Q_CAP_C0805-22UF,16V,20%,X6S,CA 1        P5V_AUX                 
                                  2        GND                     
PC215            Q_CAP_C0805-22UF,16V,20%,X6S,CA 1        P5V_AUX                 
                                  2        GND                     
PC216            Q_CAP_0402-0.22UF,16V,10%,X7R,A 1        SW_P5V_AUX_BST          
                                  2        SW_P5V_AUX_SW           
PC217            Q_CAP_C0805-22UF,16V,20%,X6S,CA 1        P5V_AUX                 
                                  2        GND                     
PC218            Q_CAP_C0805-10UF,25V,10%,X6S,CA 1        SW_P3V3_AUX_FLT         
                                  2        GND                     
PC219            Q_CAP_C0805-10UF,25V,10%,X6S,CA 1        SW_P3V3_AUX_FLT         
                                  2        GND                     
PC221            Q_CAP_C0402-1UF,25V,10%,X6S,CHA 1        P3V3_AUX_VCC            
                                  2        GND                     
PC223            Q_CAP_0402-0.1UF,25V,10%,X7R,CA 1        SW_P3V3_AUX_FLT         
                                  2        GND                     
PC224            Q_CAP_0402-0.22UF,16V,10%,X7R,A 1        SW_P3V3_AUX_BST         
                                  2        SW_P3V3_AUX_SW          
PC225            Q_CAP_0402-0.1UF,25V,10%,X7R,CA 1        P3V3_AUX                
                                  2        GND                     
PC226            Q_CAP_C0805-22UF,10V,20%,X6S,CA 1        P3V3_AUX                
                                  2        GND                     
PC227            Q_CAP_C0805-22UF,10V,20%,X6S,CA 1        P3V3_AUX                
                                  2        GND                     
PC228            Q_CAP_C0805-22UF,10V,20%,X6S,CA 1        P3V3_AUX                
                                  2        GND                     
PC229            Q_CAP_C0805-22UF,10V,20%,X6S,CA 1        P3V3_AUX                
                                  2        GND                     
PC233            Q_CAP_C0402-1UF,25V,10%,X6S,CHA 1        P5V_AUX                 
                                  2        GND                     
PC235            Q_CAP_0402-0.1UF,25V,10%,X7R,CA 1        P2V5_AUX                
                                  2        GND                     
PC237            Q_CAP_C0805-10UF,25V,10%,X6S,CA 1        P2V5_AUX                
                                  2        GND                     
PC239            Q_CAP_0402-100PF,50V,5%,NPO,CHA 1        P3V3_AUX_FB_RC          
                                  2        P3V3_AUX                
PC242            Q_CAP_C0805-10UF,25V,10%,X6S,CA 1        P3V3_AUX                
                                  2        GND                     
PC243            Q_CAP_C0402-1UF,25V,10%,X6S,CHA 1        P5V_AUX                 
                                  2        GND                     
PC248            Q_CAP_C0805-10UF,25V,10%,X6S,CA 1        P1V8_AUX                
                                  2        GND                     
PC249            Q_CAP_0402-0.1UF,25V,10%,X7R,CA 1        P1V8_AUX                
                                  2        GND                     
PC250            Q_CAP_C0402-1UF,25V,10%,X6S,CHA 1        P1V2_AUX_VCC            
                                  2        GND                     
PC251            Q_CAP_C0805-10UF,25V,10%,X6S,CA 1        SW_P1V2_AUX_FLT         
                                  2        GND                     
PC252            Q_CAP_C0805-10UF,25V,10%,X6S,CA 1        SW_P1V2_AUX_FLT         
                                  2        GND                     
PC253            Q_CAP_0402-0.1UF,25V,10%,X7R,CA 1        SW_P1V2_AUX_FLT         
                                  2        GND                     
PC254            Q_CAP_0402-0.22UF,16V,10%,X7R,A 1        SW_P1V2_AUX_BST         
                                  2        SW_P1V2_AUX_SW          
PC255            Q_CAP_0402-0.1UF,25V,10%,X7R,CA 1        P1V2_AUX                
                                  2        GND                     
PC256            Q_CAP_0805-22UF,4V,20%,X6S,TMPA 1        P1V2_AUX                
                                  2        GND                     
PC257            Q_CAP_0805-22UF,4V,20%,X6S,TMPA 1        P1V2_AUX                
                                  2        GND                     
PC258            Q_CAP_0805-22UF,4V,20%,X6S,TMPA 1        P1V2_AUX                
                                  2        GND                     
PC259            Q_CAP_0805-22UF,4V,20%,X6S,TMPA 1        P1V2_AUX                
                                  2        GND                     
PC260            Q_CAP_C0402-1UF,25V,10%,X6S,CHA 1        P1V0_AUX_VCC            
                                  2        GND                     
PC261            Q_CAP_C0805-10UF,25V,10%,X6S,CA 1        SW_P1V0_AUX_FLT         
                                  2        GND                     
PC262            Q_CAP_C0805-10UF,25V,10%,X6S,CA 1        SW_P1V0_AUX_FLT         
                                  2        GND                     
PC263            Q_CAP_0402-0.1UF,25V,10%,X7R,CA 1        SW_P1V0_AUX_FLT         
                                  2        GND                     
PC264            Q_CAP_0402-0.22UF,16V,10%,X7R,A 1        SW_P1V0_AUX_BST         
                                  2        SW_P1V0_AUX_SW          
PC266            Q_CAP_0402-0.1UF,25V,10%,X7R,CA 1        P1V0_AUX                
                                  2        GND                     
PC267            Q_CAP_0805-22UF,4V,20%,X6S,TMPA 1        P1V0_AUX                
                                  2        GND                     
PC268            Q_CAP_0805-22UF,4V,20%,X6S,TMPA 1        P1V0_AUX                
                                  2        GND                     
PC269            Q_CAP_0805-22UF,4V,20%,X6S,TMPA 1        P1V0_AUX                
                                  2        GND                     
PC270            Q_CAP_0805-22UF,4V,20%,X6S,TMPA 1        P1V0_AUX                
                                  2        GND                     
PC271            Q_CAP_0402-0.1UF,25V,10%,X7R,CA 1        P5V_AUX_REF             
                                  2        GND                     
PC272            Q_CAP_C0402-68PF,50V,5%,COG,CHA 1        P5V_AUX_FB              
                                  2        P5V_AUX                 
PC273            Q_CAP_0402-3300PF,50V,10%,X7R,A 1        P3V3_AUX_REF            
                                  2        GND                     
PC307            Q_CAP_C0805-10UF,25V,10%,X6S,CA 1        P3V3_AUX                
                                  2        GND                     
PL4              Q_INDUCTOR_SMLF-BLM18SN220TN1DA 1        P12V_AUX                
                                  2        SW_P5V_AUX_FLT          
PL19             Q_INDUCTOR_SMLF-BLM18SN220TN1DA 1        P12V_AUX                
                                  2        SW_P3V3_AUX_FLT         
PL29             Q_INDUCTOR_SMLF-BLM18SN220TN1DA 1        P12V_AUX                
                                  2        SW_P1V2_AUX_FLT         
PL31             Q_INDUCTOR_SMLF-1UH,IND,CV-10BA 1        SW_P1V2_AUX_SW          
                                  2        P1V2_AUX                
PL32             Q_INDUCTOR_SMLF-BLM18SN220TN1DA 1        P12V_AUX                
                                  2        SW_P1V0_AUX_FLT         
PL33             Q_INDUCTOR_SMLF-1UH,IND,CV-10BA 1        SW_P1V0_AUX_SW          
                                  2        P1V0_AUX                
PL34             Q_INDUCTOR_SMLF-4.7UH,IND,CV-4A 1        SW_P5V_AUX_SW           
                                  2        P5V_AUX                 
PL35             Q_INDUCTOR_SMLF-3.3UH/6A,IND,CA 1        SW_P3V3_AUX_SW          
                                  2        P3V3_AUX                
PR193            Q_RES_0402LF-0,5%,1/16W,CHIP,CA 1        P3V3_AUX                
                                  2        PVCC2_AUX               
PR205            Q_RES_0402LF-0,5%,1/16W,EMPTY,A 1        P5V_AUX                 
                                  2        PVCC2_AUX               
PR241            Q_RES_0402LF-51.1K,1%,1/16W,CHA 1        P5V_AUX_VCC             
                                  2        PWRGD_P5V_AUX_R         
PR242            Q_RES_0402LF-10K,1%,1/16W,CHIPA 1        P3V3_AUX                
                                  2        PWRGD_P3V3_AUX_R        
PR244            Q_RES_0402LF-10K,1%,1/16W,CHIPA 1        P3V3_AUX                
                                  2        PWRGD_P2V5_AUX_R        
PR245            Q_RES_0402LF-100K,1%,1/16W,CHIA 1        PWRGD_P5V_AUX_R         
                                  2        GND                     
PR255            Q_RES_0402LF-10K,1%,1/16W,CHIPA 1        P3V3_AUX                
                                  2        PWRGD_P1V8_AUX_R        
PR274            Q_RES_0402LF-0,5%,1/16W,CHIP,CA 1        P3V3_AUX                
                                  2        PVCC1_AUX               
PR275            Q_RES_0402LF-0,5%,1/16W,EMPTY,A 1        P5V_AUX                 
                                  2        PVCC1_AUX               
PR276            Q_RES_0402LF-8.66K,1%,1/16W,CHA 1        GND                     
                                  2        P3V3_AUX_CS             
PR496            Q_RES_0402LF-150K,1%,1/16W,CHIA 1        P1V2_AUX_MODE           
                                  2        GND                     
PR498            Q_RES_0402LF-10K,1%,1/16W,CHIPA 1        P3V3_AUX                
                                  2        PWRGD_P1V2_AUX_R        
PR500            Q_RES_0402LF-10K,1%,1/16W,CHIPA 1        P3V3_AUX                
                                  2        PWRGD_P1V0_AUX_R        
PR521            Q_RES_0402LF-681K,1%,1/16W,CHIA 1        P12V_AUX                
                                  2        EN_P5V_AUX              
PR522            Q_RES_0402LF-100K,1%,1/16W,CHIA 1        EN_P5V_AUX              
                                  2        GND                     
PR525            Q_RES_0402LF-13.3K,1%,1/16W,CHA 1        P5V_AUX_CS              
                                  2        GND                     
PR526            Q_RES_0402LF-12.4K,1%,1/16W,CHA 1        P5V_AUX_FB              
                                  2        GND                     
PR527            Q_RES_0402LF-91K,1%,1/16W,CHIPA 1        P5V_AUX_FB              
                                  2        P5V_AUX                 
PR530            Q_RES_0402LF-12.4K,1%,1/16W,CHA 1        GND                     
                                  2        P3V3_AUX_FB_RC          
PR532            Q_RES_0402LF-60.4K,1%,1/16W,CHA 1        GND                     
                                  2        P3V3_AUX_MODE           
PR534            Q_RES_0402LF-56K,1%,1/16W,CHIPA 1        P3V3_AUX_FB_RC          
                                  2        P3V3_AUX                
PR539            Q_RES_0402LF-5.1,5%,1/16W,CHIPA 1        PVCC1_AUX               
                                  2        P1V2_AUX_VCC            
PR541            Q_RES_0402LF-5.1,5%,1/16W,CHIPA 1        PVCC2_AUX               
                                  2        P1V0_AUX_VCC            
PR543            Q_RES_0402LF-100K,0.1%,1/16W,CA 1        P1V0_AUX_MODE           
                                  2        GND                     
PU1              MPQ8626GDZ-MPQ8626GD-Z,SMLF,ICA 1        GND                     
                                  2        SW_P3V3_AUX_SW          
                                  3        SW_P3V3_AUX_FLT         
                                  4        P3V3_AUX_CS             
                                  5        PWRGD_P5V_AUX_R2        
                                  6        P3V3_AUX_FB_RC          
                                  7        GND                     
                                  8        P3V3_AUX_REF            
                                  9        PWRGD_P3V3_AUX_R        
                                  10       SW_P3V3_AUX_BST         
                                  11       SW_P3V3_AUX_SW          
                                  12       P3V3_AUX_MODE           
                                  13       P3V3_AUX_VCC            
                                  14       GND                     
PU38             MPQ8633AGLEC807Z-MPQ8633AGLE-CA 1        SW_P5V_AUX_BST          
                                  11_18    GND                     
                                  2        GND                     
                                  3        P5V_AUX_CS              
                                  4        GND                     
                                  5        P5V_AUX_REF             
                                  6        GND                     
                                  7        P5V_AUX_FB              
                                  8        EN_P5V_AUX              
                                  9        PWRGD_P5V_AUX_R         
                                  10       SW_P5V_AUX_FLT          
                                  19       P5V_AUX_VCC             
                                  20       SW_P5V_AUX_SW           
                                  21       SW_P5V_AUX_FLT          
PU39             RT9059GQW-RT9059GQW,SMLF,IC,ALA 1        P2V5_AUX                
                                  2        P2V5_AUX                
                                  3        P2V5_AUX                
                                  4        PU39_ADJ                
                                  5        PWRGD_P2V5_AUX_R        
                                  6        PWRGD_P3V3_AUX_R2       
                                  7        P3V3_AUX                
                                  8        P3V3_AUX                
                                  9        P3V3_AUX                
                                  10       P5V_AUX                 
                                  TH       GND                     
PU40             RT9059GQW-RT9059GQW,SMLF,IC,ALA 1        P1V8_AUX                
                                  2        P1V8_AUX                
                                  3        P1V8_AUX                
                                  4        PU40_ADJ                
                                  5        PWRGD_P1V8_AUX_R        
                                  6        PWRGD_P2V5_AUX_R2       
                                  7        P3V3_AUX                
                                  8        P3V3_AUX                
                                  9        P3V3_AUX                
                                  10       P5V_AUX                 
                                  TH       GND                     
PU41             NB695GDZ-NB695GD-Z,SMLF,IC,AL0A 1        SW_P1V2_AUX_FLT         
                                  2        GND                     
                                  3        GND                     
                                  4        GND                     
                                  5        EN_P1V2_AUX             
                                  6        P1V2_AUX_VCC            
                                  7        P1V2_AUX_MODE           
                                  8        SW_P1V2_AUX_SW          
                                  9        SW_P1V2_AUX_BST         
                                  10       P1V2_AUX_VCC            
                                  11       GND                     
                                  12       P1V2_AUX                
                                  13       PWRGD_P1V2_AUX_R        
PU42             NB695GDZ-NB695GD-Z,SMLF,IC,AL0A 1        SW_P1V0_AUX_FLT         
                                  2        GND                     
                                  3        P1V0_AUX_VCC            
                                  4        GND                     
                                  5        PWRGD_P1V2_AUX_R2       
                                  6        P1V0_AUX_VCC            
                                  7        P1V0_AUX_MODE           
                                  8        SW_P1V0_AUX_SW          
                                  9        SW_P1V0_AUX_BST         
                                  10       P1V0_AUX_VCC            
                                  11       GND                     
                                  12       P1V0_AUX                
                                  13       PWRGD_P1V0_AUX_R        
Q1               MMBT39047F-MMBT3904-7-F,SMLF,IA B        BJT_Q3_C                
                                  C        RST_BMC_EXTRST_R2_N     
                                  E        GND                     
Q2               MOSFET_NCH_DUAL-2N7002KDW,SMLFA 1        V_BMC_DDC_SDA           
                                  2        V_BMC_DDC_LS_GATE       
                                  3        V_BMC_LS_DDC_SCL        
                                  4        V_BMC_DDC_SCL           
                                  5        V_BMC_DDC_LS_GATE       
                                  6        V_BMC_LS_DDC_SDA        
Q3               MMBT39047F-MMBT3904-7-F,SMLF,IA B        BJT_Q3_B                
                                  C        BJT_Q3_C                
                                  E        GND                     
Q7               MOSFET_N_123-BSS123-7-F,SMLF,IA 1        LPC_ESPI_SEL_R1         
                                  2        SPI_BMC_CPLD_R_MOSI     
                                  3        Q7_D                    
Q8               MOSFET_DUAL_6P-DMN2400UV-7,SMLA 1        PGPPA_BMC_AUX_L         
                                  2        LPC_ESPI_SEL_LV5        
                                  3        P1V8_AUX                
                                  4        PGPPA_BMC_AUX_L         
                                  5        LPC_ESPI_SEL_N          
                                  6        P3V3_AUX                
Q9               MOSFET_N_GSD-DMG6968U-7,SMLF,IA D        LPC_ESPI_SEL_LV5        
                                  G        LPC_ESPI_SEL_N          
                                  S        GND                     
Q10              MOSFET_N_GSD-DMG6968U-7,SMLF,IA D        LPC_ESPI_SEL_N          
                                  G        LPC_ESPI_SEL_R          
                                  S        GND                     
Q11              MOSFET_N_GSD-NX7002AK,SMLF,IC,A D        P3V_BAT_R1              
                                  G        BATTERY_DETECT_R        
                                  S        P3V_BAT_SENSOR          
Q12              MOSFET_DUAL_6P-2N7002KDW,SMLF,A 1        GND                     
                                  2        PWR_LED                 
                                  3        ID_LED_BUF              
                                  4        FM_ID_LED_N             
                                  5        P3V3_LED                
                                  6        PWR_LED_BUF             
R1               Q_RES_0402LF-0,5%,1/16W,EMPTY,A 1        M_BMC_DDR4_BG1          
                                  2        M_BMC_DDR4_MBG1         
R2               Q_RES_0402LF-0,5%,1/16W,CHIP,CA 1        M_BMC_DDR4_BG1          
                                  2        GND                     
R3               Q_RES_0402LF-0,5%,1/16W,CHIP,CA 1        M_BMC_DDR4_ZQU          
                                  2        GND                     
R4               Q_RES_0402LF-1K,1%,1/16W,CHIP,A 1        PD_M_BMC_DDR4_PAR       
                                  2        GND                     
R5               Q_RES_0402LF-1K,1%,1/16W,CHIP,A 1        PD_M_BMC_DDR4_TEN       
                                  2        GND                     
R6               Q_RES_0402LF-240,1%,1/16W,CHIPA 1        PD_M_BMC_DDR4_ZQ        
                                  2        GND                     
R7               Q_RES_0402LF-60.4,1%,1/16W,CHIA 1        M_BMC_DDR4_MCLK_DN      
                                  2        M_BMC_DDR4_MCLK_C       
R8               Q_RES_0402LF-60.4,1%,1/16W,CHIA 1        M_BMC_DDR4_MCLK_DP      
                                  2        M_BMC_DDR4_MCLK_C       
R9               Q_RES_0402LF-4.7K,5%,1/16W,CHIA 1        M_BMC_DDR4_ALERT_N      
                                  2        P1V2_AUX                
R10              Q_RES_0402LF-10K,1%,1/16W,CHIPA 1        P3V3_AUX                
                                  2        DP_BMC_AUX_C_N          
R11              Q_RES_0402LF-4.7K,1%,1/16W,CHIA 1        P3V3_AUX                
                                  2        FM_BMC_DEBUG_SW_N       
R12              Q_RES_0402LF-4.7K,5%,1/16W,CHIA 1        P3V3_AUX                
                                  2        FRU_E0                  
R13              Q_RES_0402LF-4.7K,5%,1/16W,EMPA 1        P3V3_AUX                
                                  2        FRU_E1                  
R14              Q_RES_0402LF-4.7K,5%,1/16W,EMPA 1        P3V3_AUX                
                                  2        FRU_E2                  
R15              Q_RES_0402LF-1K,1%,1/16W,CHIP,A 1        PD_FRU_WC_N             
                                  2        GND                     
R16              Q_RES_0402LF-2.21K    ,1%  ,1/A 1        V_BMC_LS_DDC_SCL_R      
                                  2        CRT_VCC5                
R17              Q_RES_0402LF-2.21K    ,1%  ,1/A 1        V_BMC_LS_DDC_SDA_R      
                                  2        CRT_VCC5                
R18              Q_RES_0402LF-0,5%,1/16W,CHIP,CA 1        P5V_AUX                 
                                  2        BMC_DDC_BUF_PWR         
R19              Q_RES_0402LF-0,5%,1/16W,CHIP,CA 1        V_VGAHS_R               
                                  2        V_VGAHS                 
R20              Q_RES_0402LF-0,5%,1/16W,CHIP,CA 1        V_VGAVS_R               
                                  2        V_VGAVS                 
R21              Q_RES_0402LF-0,5%,1/16W,CHIP,CA 1        V_DACG_R                
                                  2        V_DACG                  
R22              Q_RES_0402LF-150,1%,1/16W,CHIPA 1        V_DACB_R                
                                  2        GND                     
R23              Q_RES_0402LF-150,1%,1/16W,CHIPA 1        V_DACG_R                
                                  2        GND                     
R24              Q_RES_0402LF-0,5%,1/16W,CHIP,CA 1        V_DACB_R                
                                  2        V_DACB                  
R25              Q_RES_0402LF-150,1%,1/16W,CHIPA 1        V_DACR_R                
                                  2        GND                     
R26              Q_RES_0402LF-0,5%,1/16W,CHIP,CA 1        V_DACR_R                
                                  2        V_DACR                  
R27              Q_RES_0603-0,5%,1/10W,EMPTY,TMA 1        P5V_AUX                 
                                  2        CRT_VCC5                
R28              Q_RES_0402LF-33       ,1%  ,1/A 1        V_BMC_LS_DDC_SCL        
                                  2        V_BMC_LS_DDC_SCL_R      
R29              Q_RES_0402LF-33       ,1%  ,1/A 1        V_BMC_LS_DDC_SDA        
                                  2        V_BMC_LS_DDC_SDA_R      
R30              Q_RES_0402LF-0,5%,1/16W,CHIP,CA 1        CRT_VCC5                
                                  2        BMC_DDC_BUF_EN          
R31              Q_RES_0402LF-4.7K,1%,1/16W,CHIA 1        P3V3_RGM                
                                  2        V_BMC_DDC_SDA           
R32              Q_RES_0402LF-4.7K,1%,1/16W,CHIA 1        P3V3_RGM                
                                  2        V_BMC_DDC_SCL           
R33              Q_RES_0402LF-33       ,1%  ,1/B 1        SMB_BMC_MM15_SDA        
                                  2        SMB_BMC_TPM_MM15_SDA    
R34              Q_RES_0402LF-4.7K,5%,1/16W,CHIA 1        P3V3_AUX                
                                  2        RST_PLTRST_N            
R35              Q_RES_0402LF-0,5%,1/16W,CHIP,CA 1        PWRGD_P2V5_AUX          
                                  2        PWRGD_P2V5_AUX_R        
R36              Q_RES_0402LF-33       ,1%  ,1/A 1        SMB_BMC_MM14_SCL        
                                  2        SMB_BMC_MM14_R1_SCL     
R37              Q_RES_0402LF-33       ,1%  ,1/A 1        IRQ_SMI_ACTIVE_GF_N     
                                  2        IRQ_SMI_ACTIVE_BMC_N    
R38              Q_RES_0402LF-4.7K,5%,1/16W,EMPA 1        P3V3_AUX                
                                  2        FM_BMC_SUSACK_N         
R39              Q_RES_0402LF-0,5%,1/16W,CHIP,CA 1        SPA_SOUT_SW_DBG         
                                  2        SPA_SOUT_SW_BUF         
R40              Q_RES_0402LF-2K,1%,1/16W,EMPTYA 1        GND                     
                                  2        PWRGD_SYS_PWROK         
R41              Q_RES_0402LF-10K,1%,1/16W,CHIPA 1        P3V3_AUX                
                                  2        LPC_ESPI_SEL            
R42              Q_RES_0402LF-10K,1%,1/16W,CHIPA 1        P3V3_AUX                
                                  2        Q7_D                    
R43              Q_RES_0402LF-0,5%,1/16W,EMPTY,A 1        SPA_SOUT_SW_MNUSB       
                                  2        SPA_SOUT_SW_BUF         
R44              Q_RES_0402LF-4.7K,5%,1/16W,CHIA 1        P3V3_AUX                
                                  2        SYS_PWRBTN_N            
R45              Q_RES_0402LF-4.7K,5%,1/16W,CHIA 1        P3V3_AUX                
                                  2        FM_THROTTLE_N           
R46              Q_RES_0402LF-33       ,1%  ,1/A 1        SMB_BMC_MM14_SDA        
                                  2        SMB_BMC_MM14_R1_SDA     
R47              Q_RES_0402LF-33       ,1%  ,1/B 1        SMB_BMC_TPM_MM15_SCL    
                                  2        SMB_BMC_MM15_SCL        
R48              Q_RES_0402LF-33       ,1%  ,1/B 1        BMC_EMMC_CMD            
                                  2        EMMC_CMD_R              
R49              Q_RES_0402LF-0,5%,1/16W,CHIP,CA 1        PWRGD_P1V0_AUX          
                                  2        PWRGD_P1V0_AUX_R2       
R50              Q_RES_0402LF-10K,1%,1/16W,CHIPA 1        P3V3_AUX                
                                  2        FM_TPM_PRSNT_1_N        
R51              Q_RES_0402LF-0,5%,1/16W,CHIP,CA 1        H_CPU0_PROCHOT_LVC1_N   
                                  2        H_CPU0_PROCHOT_LVC1_R_N 
R52              Q_RES_0402LF-33       ,1%  ,1/A 1        RGMII_BMC_RX_CTRL       
                                  2        RGMII_BMC_RX_R_CTRL     
R53              Q_RES_0402LF-33       ,1%  ,1/A 1        RGMII_BMC_RXD_<0>       
                                  2        RGMII_BMC_R_RXD_<0>     
R54              Q_RES_0402LF-33       ,1%  ,1/A 1        RGMII_BMC_RXD_<1>       
                                  2        RGMII_BMC_R_RXD_<1>     
R55              Q_RES_0402LF-4.7K,5%,1/16W,CHIA 1        P3V3_AUX                
                                  2        FM_BMC_READY_R_PLD_N    
R56              Q_RES_0402LF-4.7K,5%,1/16W,CHIA 1        P3V3_AUX                
                                  2        FM_BIOS_DEBUG_EN_R_N    
R57              Q_RES_0402LF-4.7K,5%,1/16W,CHIA 1        P3V3_AUX                
                                  2        FM_RISER1_JTAG_SEL_R_N  
R58              Q_RES_0402LF-4.7K,5%,1/16W,CHIA 1        P3V3_AUX                
                                  2        FM_RISER2_JTAG_SEL_R_N  
R59              Q_RES_0402LF-10K,1%,1/16W,CHIPA 1        P3V3_AUX                
                                  2        IRQ_TPM_SPI_N           
R60              Q_RES_0402LF-33       ,1%  ,1/A 1        BMC_CPLD_GPIO_1         
                                  2        BMC_CPLD_GPIO_1_R1      
R61              Q_RES_0402LF-4.7K,5%,1/16W,CHIA 1        P3V3_AUX                
                                  2        IRQ_BMC_PCH_NMI_N       
R62              Q_RES_0402LF-4.7K,5%,1/16W,CHIA 1        P3V3_AUX                
                                  2        FM_PCH_BMC_THERMTRIP_N  
R63              Q_RES_0402LF-0,5%,1/16W,EMPTY,A 1        SGPIO_CLK_1             
                                  2        GND                     
R64              Q_RES_0402LF-0,5%,1/16W,EMPTY,A 1        SGPIO_CLK_0             
                                  2        GND                     
R65              Q_RES_0402LF-33       ,1%  ,1/A 1        BMC_CPLD_GPIO_2         
                                  2        BMC_CPLD_GPIO_2_R1      
R66              Q_RES_0402LF-100K,1%,1/16W,CHIA 1        GND                     
                                  2        PWRGD_PSU_AC_PWROK      
R67              Q_RES_0402LF-4.7K,1%,1/16W,CHIA 1        P3V3_AUX                
                                  2        UART_BMC_5_TXD_BUF      
R68              Q_RES_0402LF-4.7K,5%,1/16W,CHIA 1        P3V3_AUX                
                                  2        IRQ_SGPIO_N             
R69              Q_RES_0402LF-4.7K,5%,1/16W,CHIA 1        P3V3_AUX                
                                  2        RST_SGPIO_RESET_N       
R70              Q_RES_0402LF-4.7K,5%,1/16W,CHIA 1        P3V3_AUX                
                                  2        PU_SPI_BMC_BOOT_MISO    
R71              Q_RES_0402LF-33       ,1%  ,1/A 1        SMB_BMC_MM5_R_SCL       
                                  2        SMB_BMC_MM5_SCL         
R72              Q_RES_0402LF-4.7K,1%,1/16W,EMPA 1        P3V3_AUX                
                                  2        UART_BMC_5_RXD_BUF_R    
R73              Q_RES_0402LF-1K,1%,1/16W,EMPTYA 1        P3V3_AUX                
                                  2        SGPIO_LD_1              
R74              Q_RES_0402LF-2K,1%,1/16W,CHIP,A 1        P3V3_AUX                
                                  2        SGPIO_DI_1              
R75              Q_RES_0402LF-2K,1%,1/16W,CHIP,A 1        P3V3_AUX                
                                  2        SGPIO_DO_1              
R76              Q_RES_0402LF-2K,1%,1/16W,CHIP,A 1        P3V3_AUX                
                                  2        SGPIO_CLK_1             
R77              Q_RES_0402LF-1K,1%,1/16W,EMPTYA 1        P3V3_AUX                
                                  2        SGPIO_LD_0              
R78              Q_RES_0402LF-2K,1%,1/16W,CHIP,A 1        P3V3_AUX                
                                  2        SGPIO_DI_0              
R79              Q_RES_0402LF-2K,1%,1/16W,CHIP,A 1        P3V3_AUX                
                                  2        SGPIO_DO_0              
R80              Q_RES_0402LF-33       ,1%  ,1/B 1        SYS_PWRBTN_N            
                                  2        PWR_BTN_BMC_N           
R81              Q_RES_0402LF-4.7K,5%,1/16W,CHIA 1        P3V3_AUX                
                                  2        PWR_BTN_BMC_N           
R82              Q_RES_0402LF-2K,1%,1/16W,CHIP,A 1        P3V3_AUX                
                                  2        SGPIO_CLK_0             
R83              Q_RES_0402LF-0,5%,1/16W,CHIP,CA 1        SPA_SIN_SW_DBG          
                                  2        SPA_SIN_SW_BUF          
R84              Q_RES_0402LF-33       ,1%  ,1/A 1        V_VGAVS_BUF_R           
                                  2        V_VGAVS_BUF             
R85              Q_RES_0402LF-33       ,1%  ,1/A 1        V_VGAHS_BUF_R           
                                  2        V_VGAHS_BUF             
R86              Q_RES_0402LF-0,5%,1/16W,CHIP,CA 1        P3V3_RGM                
                                  2        V_BMC_DDC_LS_GATE       
R87              Q_RES_0402LF-150,1%,1/16W,CHIPA 1        V_DACB_IO               
                                  2        GND                     
R88              Q_RES_0402LF-150,1%,1/16W,CHIPA 1        V_DACG_IO               
                                  2        GND                     
R89              Q_RES_0402LF-150,1%,1/16W,CHIPA 1        V_DACR_IO               
                                  2        GND                     
R90              Q_RES_0402LF-33       ,1%  ,1/A 1        FM_RISER2_JTAG_SEL_R_N  
                                  2        FM_RISER2_JTAG_SEL_N    
R91              Q_RES_0402LF-2.2K ,5%,1/16W,CHA 1        CRT_VCC5                
                                  2        V_BMC_LS_DDC_SDA        
R92              Q_RES_0402LF-2.2K ,5%,1/16W,CHA 1        CRT_VCC5                
                                  2        V_BMC_LS_DDC_SCL        
R93              Q_RES_0402LF-33       ,1%  ,1/A 1        SMB_BMC_MM5_R_SDA       
                                  2        SMB_BMC_MM5_SDA         
R94              Q_RES_0402LF-100,1%,1/16W,CHIPA 1        PD_SPI_BMC_BOOT_MOSI    
                                  2        GND                     
R95              Q_RES_0402LF-0,5%,1/16W,EMPTY,A 1        SPA_SIN_SW_MNUSB        
                                  2        SPA_SIN_SW_BUF          
R96              Q_RES_0402LF-33       ,1%  ,1/A 1        BMC_CPLD_GPIO_25_R1     
                                  2        BMC_CPLD_GPIO_25        
R97              Q_RES_0402LF-0,5%,1/16W,CHIP,CA 1        SPI_BMC_TPM_MOSI_R      
                                  2        SPI_BMC_MOSI_IO0_R      
R98              Q_RES_0402LF-0,5%,1/16W,CHIP,CA 1        SPI_BMC_TPM_MISO_R      
                                  2        SPI_BMC_MISO_IO1_R      
R99              Q_RES_0402LF-0,5%,1/16W,CHIP,CA 1        PWRGD_P3V3_RGM_R        
                                  2        PWRGD_P3V3_RGM          
R100             Q_RES_0402LF-0,5%,1/16W,CHIP,CA 1        SPI_BMC_TPM_CS2_N_R     
                                  2        SPI_BMC_TPM_CS2_R_N     
R101             Q_RES_0402LF-4.7K,5%,1/16W,CHIA 1        P3V3_AUX                
                                  2        RMII_RXER               
R102             Q_RES_0402LF-33       ,1%  ,1/A 1        UART_BMC_5_TXD_BUF      
                                  2        UART_BMC_5_TXD_BUF_R    
R103             Q_RES_0402LF-4.7K,5%,1/16W,CHIA 1        P3V3_AUX                
                                  2        RMII_TXEN               
R104             Q_RES_0402LF-33       ,1%  ,1/A 1        UART_BMC_5_RXD_BUF_R    
                                  2        UART_BMC_5_RXD_R        
R105             Q_RES_0402LF-10K,1%,1/16W,EMPTA 1        P3V3_AUX                
                                  2        FM_MB_STBY_EN           
R106             Q_RES_0402LF-0,5%,1/16W,CHIP,CA 1        RST_BMC_SRST_N          
                                  2        RST_BMC_EXTRST_R2_N     
R107             Q_RES_0402LF-33       ,1%  ,1/B 1        QSPI_2_PLD_CS1_N        
                                  2        SPI_BMC_BOOT_CS1_R1_N   
R108             Q_RES_0402LF-49.9     ,1%  ,1/A 1        RST_SRST_PLD_BMC_BUF_N  
                                  2        RST_BMC_SRST_BUF_R_N    
R109             Q_RES_0402LF-0,5%,1/16W,CHIP,CA 1        SPI_BMC_TPM_CLK_R       
                                  2        SPI_BMC_CLK_R           
R110             Q_RES_0402LF-0,5%,1/16W,CHIP,CA 1        RST_BMC_EXTRST_R3_N     
                                  2        RST_BMC_EXTRST_R2_N     
R111             Q_RES_0402LF-33       ,1%  ,1/A 1        FM_BMC_READY_R_PLD_N    
                                  2        FM_BMC_READY_PLD_N      
R112             Q_RES_0402LF-33       ,1%  ,1/A 1        FM_BIOS_DEBUG_EN_R_N    
                                  2        FM_BIOS_DEBUG_EN_N      
R113             Q_RES_0402LF-0,5%,1/16W,CHIP,CA 1        IRQ_TPM_SPI_N           
                                  2        IRQ_BMC_TPM_SPI_R_N     
R114             Q_RES_0402LF-33       ,1%  ,1/A 1        FM_MB_STBY_EN           
                                  2        FM_MB_STBY_R_EN         
R115             Q_RES_0402LF-4.7K,5%,1/16W,CHIA 1        PGPPA_BMC_AUX           
                                  2        ESPI_HOST_LPC_BMC_LFRAME_N
R116             Q_RES_0402LF-4.7K,5%,1/16W,CHIA 1        PGPPA_BMC_AUX           
                                  2        IRQ_BMC_LPC_SERIRQ_ESPI_GF
R117             Q_RES_0402LF-4.7K,5%,1/16W,CHIA 1        PGPPA_BMC_AUX           
                                  2        RST_BMC_LPC_ESPI_N      
R118             Q_RES_0402LF-100K,1%,1/16W,EMPA 1        GND                     
                                  2        RST_PLTRST_N            
R119             Q_RES_0402LF-33       ,1%  ,1/A 1        IRQ_BMC_LPC_SERIRQ_ESPI_GF
                                  2        IRQ_ESPI_LPC_SERIRQ_ALERT0_N
R120             Q_RES_0402LF-33       ,1%  ,1/A 1        RST_BMC_LPC_ESPI_N      
                                  2        RST_ESPI_LPC_BMC_N      
R121             Q_RES_0402LF-33       ,1%  ,1/A 1        FM_CPU_MSMI_CATERR_LVT3_N
                                  2        FM_CPU_RMCA_CATERR_LVT3_R_N
R122             Q_RES_0402LF-33       ,1%  ,1/A 1        UART_1_SCM_TXD          
                                  2        UART_1_SCM_R_TXD        
R123             Q_RES_0402LF-33       ,1%  ,1/A 1        FM_TPM_PRSNT_1_N        
                                  2        FM_TPM_PRSNT_1_R_N      
R124             Q_RES_0402LF-2K,1%,1/16W,CHIP,A 1        P3V3_AUX                
                                  2        RST_BMC_SRST_BUF_R_N    
R125             Q_RES_0402LF-100,1%,1/16W,EMPTA 1        RST_BMC_SRST_BUF_R_N    
                                  2        RST_BMC_SRST_N          
R126             Q_RES_0402LF-33       ,1%  ,1/B 1        SMB_BMC_MM15_SDA        
                                  2        SMB_TPM_MM15_SDA        
R127             Q_RES_0402LF-240,1%,1/16W,CHIPA 1        GND                     
                                  2        IBMC_MIOZ               
R128             Q_RES_0402LF-33       ,1%  ,1/A 1        ESPI_LPC_D0_IO0         
                                  2        ESPI_LPC_LAD0_IO0       
R129             Q_RES_0402LF-33       ,1%  ,1/A 1        ESPI_LPC_D1_IO1         
                                  2        ESPI_LPC_LAD1_IO1       
R130             Q_RES_0402LF-33       ,1%  ,1/A 1        ESPI_LPC_D2_IO2         
                                  2        ESPI_LPC_LAD2_IO2       
R131             Q_RES_0402LF-33       ,1%  ,1/A 1        ESPI_LPC_D3_IO3         
                                  2        ESPI_LPC_LAD3_IO3       
R132             Q_RES_0402LF-33       ,1%  ,1/A 1        SMB_BMC_MM1_R_SCL       
                                  2        SMB_BMC_MM1_SCL         
R133             Q_RES_0402LF-33       ,1%  ,1/A 1        SMB_BMC_MM1_R_SDA       
                                  2        SMB_BMC_MM1_SDA         
R134             Q_RES_0402LF-100,1%,1/16W,CHIPA 1        RST_BMC_SRST_BUF_R_N    
                                  2        RST_RSTB_N              
R135             Q_RES_0402LF-0,5%,1/16W,CHIP,CA 1        SMB_BMC_MM16_SCL        
                                  2        SMB_BMC_MM16_R1_SCL     
R136             Q_RES_0402LF-33       ,1%  ,1/B 1        SMB_TPM_MM15_SCL        
                                  2        SMB_BMC_MM15_SCL        
R137             Q_RES_0402LF-33       ,1%  ,1/A 1        SMB_BMC_MM12_R_SCL      
                                  2        SMB_BMC_MM12_SCL        
R138             Q_RES_0402LF-33       ,1%  ,1/A 1        SMB_BMC_MM4_R_SCL       
                                  2        SMB_BMC_MM4_SCL         
R139             Q_RES_0402LF-33       ,1%  ,1/A 1        SMB_BMC_MM4_R_SDA       
                                  2        SMB_BMC_MM4_SDA         
R140             Q_RES_0402LF-4.7K,5%,1/16W,CHIA 1        P3V3_AUX                
                                  2        SPI_BMC_BOOT_MOSI       
R141             Q_RES_0402LF-0,5%,1/16W,CHIP,CA 1        PWRGD_P5V_AUX_R1        
                                  2        PWRGD_P5V_AUX           
R142             Q_RES_0402LF-33       ,1%  ,1/A 1        SMB_BMC_MM6_R_SCL       
                                  2        SMB_BMC_MM6_SCL         
R143             Q_RES_0402LF-33       ,1%  ,1/A 1        SMB_BMC_MM6_R_SDA       
                                  2        SMB_BMC_MM6_SDA         
R144             Q_RES_0402LF-33       ,1%  ,1/A 1        SMB_BMC_MM12_R_SDA      
                                  2        SMB_BMC_MM12_SDA        
R145             Q_RES_0402LF-4.7K,5%,1/16W,CHIA 1        P3V3_AUX                
                                  2        SMB_BMC_MM12_SCL        
R146             Q_RES_0402LF-33       ,1%  ,1/A 1        SMB_BMC_MM8_R_SCL       
                                  2        SMB_BMC_MM8_SCL         
R147             Q_RES_0402LF-33       ,1%  ,1/A 1        SMB_BMC_MM8_R_SDA       
                                  2        SMB_BMC_MM8_SDA         
R148             Q_RES_0402LF-33       ,1%  ,1/A 1        SGPIO_CLK_1             
                                  2        SGPIO_BMC_M1_CLK        
R149             Q_RES_0402LF-4.7K,5%,1/16W,CHIA 1        P3V3_AUX                
                                  2        SMB_BMC_MM12_SDA        
R150             Q_RES_0402LF-33       ,1%  ,1/A 1        SGPIO_LD_1              
                                  2        SGPIO_BMC_M1_LD         
R151             Q_RES_0402LF-33       ,1%  ,1/A 1        SGPIO_DO_1              
                                  2        SGPIO_BMC_M1_DO         
R152             Q_RES_0402LF-33       ,1%  ,1/A 1        SMB_BMC_MM16_SCL        
                                  2        SMB_BMC_MM16_R_SCL      
R153             Q_RES_0402LF-33       ,1%  ,1/A 1        SMB_BMC_MM16_SDA        
                                  2        SMB_BMC_MM16_R_SDA      
R154             Q_RES_0402LF-0,5%,1/16W,EMPTY,A 1        P1V8_AUX                
                                  2        P3V3_P2V5_P1V8_RVDD     
R155             Q_RES_0402LF-0,5%,1/16W,CHIP,CA 1        P3V3_AUX                
                                  2        P3V3_P2V5_P1V8_RVDD     
R156             Q_RES_0402LF-0,5%,1/16W,EMPTY,A 1        P2V5_AUX                
                                  2        P3V3_P2V5_P1V8_RVDD     
R157             Q_RES_0402LF-33       ,1%  ,1/A 1        UART_BMC_1_TXD_R        
                                  2        UART_BMC_1_TXD          
R158             Q_RES_0402LF-33       ,1%  ,1/A 1        FM_DBP_CPU_PREQ_GF_R_N  
                                  2        FM_DBP_CPU_PREQ_GF_N    
R159             Q_RES_0402LF-33       ,1%  ,1/A 1        FM_JTAG_TCK_MUX_BMC_SEL 
                                  2        FM_JTAG_TCK_MUX_BMC_SEL_R1
R160             Q_RES_0402LF-33       ,1%  ,1/A 1        RST_RSMRST_N            
                                  2        RST_RSMRST_R_N          
R161             Q_RES_0402LF-4.7K,5%,1/16W,CHIA 1        P3V3_AUX                
                                  2        RMII_CSRDV              
R162             Q_RES_0402LF-33       ,1%  ,1/A 1        SMB_BMC_MM15_SCL        
                                  2        SMB_BMC_MM15_R_SCL      
R163             Q_RES_0402LF-4.7K,5%,1/16W,CHIA 1        P3V3_AUX                
                                  2        FM_CPU_MSMI_CATERR_LVT3_N
R164             Q_RES_0402LF-10K,1%,1/16W,EMPTA 1        P1V8_AUX                
                                  2        BMC_EMMC_RST_N          
R165             Q_RES_0402LF-33       ,1%  ,1/A 1        SMB_BMC_MM2_R_SCL       
                                  2        SMB_BMC_MM2_SCL         
R166             Q_RES_0402LF-33       ,1%  ,1/A 1        IRQ_BMC_CPU_NMI_R       
                                  2        IRQ_BMC_CPU_NMI         
R167             Q_RES_0402LF-330,1%,1/16W,CHIPA 1        P3V3_AUX                
                                  2        BMC_HEARTBEAT_R_N       
R168             Q_RES_0402LF-33       ,1%  ,1/A 1        RST_PLTRST_N            
                                  2        RST_PLTRST_R_N          
R169             Q_RES_0402LF-4.7K,5%,1/16W,CHIA 1        P3V3_AUX                
                                  2        RST_PCA9548_SENSOR_N    
R170             Q_RES_0402LF-33       ,1%  ,1/A 1        UART_BMC_5_TXD          
                                  2        UART_BMC_5_TXD_R        
R171             Q_RES_0402LF-33       ,1%  ,1/A 1        RMII_TXEN_R             
                                  2        RMII_TXEN               
R172             Q_RES_0402LF-33       ,1%  ,1/A 1        RMII_TXD0_R             
                                  2        RMII_TXD0               
R173             Q_RES_0402LF-33       ,1%  ,1/A 1        RMII_TXD1_R             
                                  2        RMII_TXD1               
R174             Q_RES_0402LF-33       ,1%  ,1/A 1        SPI_BMC_BIOS_ROM_CLK    
                                  2        SPI_BMC_BIOS_ROM_R_CLK  
R175             Q_RES_0402LF-33       ,1%  ,1/A 1        SPI_BMC_BIOS_ROM_MOSI   
                                  2        SPI_BMC_BIOS_ROM_R_MOSI 
R176             Q_RES_0402LF-33       ,1%  ,1/A 1        SPI_BMC_BIOS_ROM_MISO   
                                  2        SPI_BMC_BIOS_ROM_R_MISO 
R177             Q_RES_0402LF-33       ,1%  ,1/A 1        H_CPU1_PROCHOT_LVC1_N   
                                  2        H_CPU1_PROCHOT_LVC1_R_N 
R178             Q_RES_0402LF-33       ,1%  ,1/A 1        SPI_BMC_CLK_R           
                                  2        SPI_BMC_BOOT_CLK        
R179             Q_RES_0402LF-33       ,1%  ,1/A 1        SPI_BMC_MOSI_IO0_R      
                                  2        SPI_BMC_BOOT_MOSI       
R180             Q_RES_0402LF-33       ,1%  ,1/A 1        SPI_BMC_MISO_IO1_R      
                                  2        SPI_BMC_BOOT_MISO       
R181             Q_RES_0402LF-33       ,1%  ,1/A 1        SPI_BMC_IO2_R           
                                  2        SPI_BMC_BOOT_IO2        
R182             Q_RES_0402LF-33       ,1%  ,1/A 1        SPI_BMC_IO3_R           
                                  2        SPI_BMC_BOOT_IO3        
R183             Q_RES_0402LF-33       ,1%  ,1/A 1        SPI_BMC_TPM_CS2_R_N     
                                  2        SPI_BMC_TPM_CS2_R1_N    
R184             Q_RES_0402LF-33       ,1%  ,1/A 1        I3C1_SPD_SCL            
                                  2        I3C1_SCL_R              
R185             Q_RES_0402LF-33       ,1%  ,1/A 1        I3C1_SPD_SDA            
                                  2        I3C1_SDA_R              
R186             Q_RES_0402LF-33       ,1%  ,1/A 1        I3C2_SPD_SCL            
                                  2        I3C2_SCL_R              
R187             Q_RES_0402LF-33       ,1%  ,1/A 1        I3C2_SPD_SDA            
                                  2        I3C2_SDA_R              
R188             Q_RES_0402LF-4.7K,5%,1/16W,CHIA 1        P1V2_P1V0_I3C_VDDL1     
                                  2        I3C3_SPD_SCL            
R189             Q_RES_0402LF-4.7K,5%,1/16W,CHIA 1        P1V2_P1V0_I3C_VDDL1     
                                  2        I3C3_SPD_SDA            
R190             Q_RES_0402LF-4.7K,5%,1/16W,CHIA 1        P1V2_P1V0_I3C_VDDL1     
                                  2        I3C2_SPD_SCL            
R191             Q_RES_0402LF-4.7K,5%,1/16W,CHIA 1        P1V2_P1V0_I3C_VDDL1     
                                  2        I3C2_SPD_SDA            
R192             Q_RES_0402LF-49.9     ,1%  ,1/A 1        PWRGD_P1V0_AUX_DELAY_BUF
                                  2        RST_BMC_SRST_BUF_R_N    
R193             Q_RES_0402LF-100K,1%,1/16W,CHIA 1        P3V3_AUX                
                                  2        SPA_SIN_SW_DBG          
R194             Q_RES_0402LF-4.7K,5%,1/16W,CHIA 1        P1V2_P1V0_I3C_VDDL1     
                                  2        I3C1_SPD_SCL            
R195             Q_RES_0402LF-4.7K,5%,1/16W,CHIA 1        P1V2_P1V0_I3C_VDDL1     
                                  2        I3C1_SPD_SDA            
R196             Q_RES_0402LF-4.7K,5%,1/16W,CHIA 1        P1V2_P1V0_I3C_VDDL1     
                                  2        I3C4_SPD_SCL            
R197             Q_RES_0402LF-4.7K,5%,1/16W,CHIA 1        P1V2_P1V0_I3C_VDDL1     
                                  2        I3C4_SPD_SDA            
R198             Q_RES_0402LF-33       ,1%  ,1/A 1        I3C3_SCL_R              
                                  2        I3C3_SPD_SCL            
R199             Q_RES_0402LF-33       ,1%  ,1/A 1        I3C3_SDA_R              
                                  2        I3C3_SPD_SDA            
R200             Q_RES_0402LF-33       ,1%  ,1/A 1        I3C4_SCL_R              
                                  2        I3C4_SPD_SCL            
R201             Q_RES_0402LF-33       ,1%  ,1/A 1        I3C4_SDA_R              
                                  2        I3C4_SPD_SDA            
R202             Q_RES_0402LF-10K,0.10%,1/16W,CA 1        GND                     
                                  2        JTAG_SCM_TCK            
R203             Q_RES_0402LF-10K,0.10%,1/16W,CA 1        P3V3_RGM                
                                  2        JTAG_SCM_TMS            
R204             Q_RES_0402LF-10K,0.10%,1/16W,CA 1        P3V3_RGM                
                                  2        JTAG_SCM_TDI            
R205             Q_RES_0402LF-20K,1%,1/16W,CHIPA 1        DEBUG_PORT_PRSNT        
                                  2        GND                     
R206             Q_RES_0402LF-47K,5%,1/16W,EMPTA 1        GND                     
                                  2        JTAG_SCM_NTRST          
R207             Q_RES_0402LF-0,5%,1/16W,CHIP,CA 1        P3V3_AUX                
                                  2        P3V3_P1V8_SD1VDD        
R208             Q_RES_0402LF-0,5%,1/16W,EMPTY,A 1        P1V8_AUX                
                                  2        P3V3_P1V8_SD1VDD        
R209             Q_RES_0402LF-10K,1%,1/16W,CHIPA 1        PECI_BMC                
                                  2        GND                     
R210             Q_RES_0402LF-10K,1%,1/16W,CHIPA 1        GND                     
                                  2        PD_SP_ENTEST            
R211             Q_RES_0402LF-10K,1%,1/16W,CHIPA 1        P3V3_RGM                
                                  2        FM_BMC_SSPRST_N         
R212             Q_RES_0402LF-4.7K,5%,1/16W,CHIA 1        P3V3_RGM                
                                  2        PU_25M_BMC_CLK_EN       
R213             Q_RES_0402LF-0,5%,1/16W,CHIP,CA 1        P3V3_AUX                
                                  2        P3V3_P1V8_SD2VDD        
R214             Q_RES_0402LF-0,5%,1/16W,EMPTY,A 1        P1V8_AUX                
                                  2        P3V3_P1V8_SD2VDD        
R215             Q_RES_0402LF-33       ,1%  ,1/A 1        BMC_CLK_25M_R           
                                  2        BMC_CLK_25M             
R216             Q_RES_0402LF-0,5%,1/16W,CHIP,CA 1        PECI_BMC_R              
                                  2        PECI_BMC                
R217             Q_RES_0402LF-0,5%,1/16W,CHIP,CA 1        USB_HOST_BMC_A_R_DP     
                                  2        USB_HOST_BMC_A_DP       
R218             Q_RES_0402LF-0,5%,1/16W,CHIP,CA 1        USB_HOST_BMC_A_R_DN     
                                  2        USB_HOST_BMC_A_DN       
R219             Q_RES_0402LF-100K,1%,1/16W,EMPB 1        DEBUG_PORT_UART_TX      
                                  2        GND                     
R220             Q_RES_0402LF-0,5%,1/16W,CHIP,CA 1        PD_INTRUDER_BMC_N       
                                  2        GND                     
R221             Q_RES_0402LF-33       ,1%  ,1/A 1        JTAG_1_BMC_TRST_R       
                                  2        JTAG_MB_TRST_N          
R222             Q_RES_0402LF-33       ,1%  ,1/A 1        JTAG_1_BMC_TCK_R        
                                  2        JTAG_MB_TCK             
R223             Q_RES_0402LF-33       ,1%  ,1/A 1        JTAG_1_BMC_TMS_R        
                                  2        JTAG_MB_TMS             
R224             Q_RES_0402LF-33       ,1%  ,1/A 1        JTAG_1_BMC_TDO_R        
                                  2        JTAG_MB_TDO             
R225             Q_RES_0402LF-33       ,1%  ,1/A 1        FM_PWR_BTN              
                                  2        PWR_BTN_BMC_N           
R226             Q_RES_0402LF-10K,0.10%,1/16W,CA 1        P3V3_AUX                
                                  2        JTAG_MB_TDI             
R227             Q_RES_0402LF-10K,0.10%,1/16W,CA 1        P3V3_AUX                
                                  2        JTAG_MB_TMS             
R228             Q_RES_0402LF-10K,0.10%,1/16W,CA 1        GND                     
                                  2        JTAG_MB_TCK             
R229             Q_RES_0402LF-4.7K,1%,1/16W,EMPA 1        GND                     
                                  2        JTAG_MB_TRST_N          
R230             Q_RES_0402LF-10K,0.10%,1/16W,CA 1        P3V3_AUX                
                                  2        JTAG_MB_TDO             
R231             Q_RES_0402LF-0,5%,1/16W,CHIP,CA 1        P3V3_AUX                
                                  2        P3V3_P1V8_I2C_I3C       
R232             Q_RES_0402LF-0,5%,1/16W,EMPTY,A 1        P1V8_AUX                
                                  2        P3V3_P1V8_I2C_I3C       
R233             Q_RES_0402LF -49.9K,1%,1/16W ,A 1        GND                     
                                  2        A_BMC_ADCREXT0          
R234             Q_RES_0402LF -49.9K,1%,1/16W ,A 1        GND                     
                                  2        A_BMC_ADCREXT1          
R235             Q_RES_0402LF-2.74K,1%,1/16W,CHA 1        GND                     
                                  2        A_BMC_DACREST           
R236             Q_RES_0402LF-33       ,1%  ,1/A 1        SMB_BMC_MM15_SDA        
                                  2        SMB_BMC_MM15_R_SDA      
R237             Q_RES_0402LF-33       ,1%  ,1/A 1        FM_DBP_BMC_PRDY_N       
                                  2        FM_DBP_BMC_PRDY_R_N     
R238             Q_RES_0402LF-4.7K,5%,1/16W,CHIA 1        P3V3_AUX                
                                  2        SPI_BMC_TPM_CS2_R_N     
R239             Q_RES_0402LF-4.7K,5%,1/16W,CHIA 1        P3V3_AUX                
                                  2        PU_BMC_FWSPIABR_N       
R240             Q_RES_0402LF-4.7K,5%,1/16W,CHIA 1        P3V3_AUX                
                                  2        PU_FWSPIWP_N            
R241             Q_RES_0402LF-4.7K,5%,1/16W,CHIA 1        P3V3_AUX                
                                  2        PU_SPI1ABR              
R242             Q_RES_0402LF-33       ,1%  ,1/A 1        FM_BMC_CPU_FBRK_OUT_R_N 
                                  2        FM_BMC_CPU_FBRK_OUT_N   
R243             Q_RES_0402LF-33       ,1%  ,1/A 1        PWRGD_PSU_AC_PWROK      
                                  2        PWRGD_PSU_AC_PWROK_R    
R244             Q_RES_0402LF-4.7K,5%,1/16W,CHIA 1        P3V3_AUX                
                                  2        SMB_BMC_MM1_SCL         
R245             Q_RES_0402LF-4.7K,5%,1/16W,CHIA 1        P3V3_AUX                
                                  2        SMB_BMC_MM1_SDA         
R246             Q_RES_0402LF-4.7K,5%,1/16W,CHIA 1        P3V3_AUX                
                                  2        SMB_BMC_MM2_SCL         
R247             Q_RES_0402LF-4.7K,5%,1/16W,CHIA 1        P3V3_AUX                
                                  2        SMB_BMC_MM2_SDA         
R248             Q_RES_0402LF-4.7K,5%,1/16W,CHIA 1        P3V3_AUX                
                                  2        SMB_BMC_MM3_SCL         
R249             Q_RES_0402LF-4.7K,5%,1/16W,CHIA 1        P3V3_AUX                
                                  2        SMB_BMC_MM3_SDA         
R250             Q_RES_0402LF-4.7K,5%,1/16W,CHIA 1        P3V3_AUX                
                                  2        SMB_BMC_MM4_SCL         
R251             Q_RES_0402LF-4.7K,5%,1/16W,CHIA 1        P3V3_AUX                
                                  2        SMB_BMC_MM4_SDA         
R252             Q_RES_0402LF-4.7K,5%,1/16W,CHIA 1        P3V3_AUX                
                                  2        SMB_BMC_MM5_R_SCL       
R253             Q_RES_0402LF-4.7K,5%,1/16W,CHIA 1        P3V3_AUX                
                                  2        SMB_BMC_MM5_R_SDA       
R254             Q_RES_0402LF-4.7K,5%,1/16W,CHIA 1        P3V3_AUX                
                                  2        SMB_BMC_MM6_SCL         
R255             Q_RES_0402LF-4.7K,5%,1/16W,CHIA 1        P3V3_AUX                
                                  2        SMB_BMC_MM6_SDA         
R256             Q_RES_0402LF-4.7K,5%,1/16W,CHIA 1        P3V3_AUX                
                                  2        SMB_BMC_MM7_R_SCL       
R257             Q_RES_0402LF-4.7K,5%,1/16W,CHIA 1        P3V3_AUX                
                                  2        SMB_BMC_MM7_R_SDA       
R258             Q_RES_0402LF-4.7K,5%,1/16W,CHIA 1        P3V3_AUX                
                                  2        SMB_BMC_MM8_SCL         
R259             Q_RES_0402LF-4.7K,5%,1/16W,CHIA 1        P3V3_AUX                
                                  2        SMB_BMC_MM8_SDA         
R260             Q_RES_0402LF-4.7K,5%,1/16W,CHIA 1        P3V3_AUX                
                                  2        SMB_BMC_MM9_SCL         
R261             Q_RES_0402LF-4.7K,5%,1/16W,CHIA 1        P3V3_AUX                
                                  2        SMB_BMC_MM9_SDA         
R262             Q_RES_0402LF-4.7K,5%,1/16W,CHIA 1        P3V3_AUX                
                                  2        SMB_BMC_MM10_SCL        
R263             Q_RES_0402LF-33       ,1%  ,1/A 1        RST_MB_STBY_N           
                                  2        RST_MB_STBY_R_N         
R264             Q_RES_0402LF-4.7K,5%,1/16W,CHIA 1        P3V3_AUX                
                                  2        SMB_BMC_MM16_SCL        
R265             Q_RES_0402LF-4.7K,5%,1/16W,CHIA 1        P3V3_AUX                
                                  2        SMB_BMC_MM16_SDA        
R266             Q_RES_0402LF-4.7K,5%,1/16W,EMPA 1        P3V3_AUX                
                                  2        FM_ME_BT_DONE           
R267             Q_RES_0402LF-4.7K,5%,1/16W,EMPA 1        P3V3_AUX                
                                  2        VOL_SEN_ALERT_R         
R268             Q_RES_0402LF-4.7K,5%,1/16W,CHIA 1        P3V3_AUX                
                                  2        SMB_BMC_ALERT3_N        
R269             Q_RES_0402LF-4.7K,5%,1/16W,CHIA 1        P3V3_AUX                
                                  2        SMB_BMC_ALERT4_N        
R270             Q_RES_0402LF-33       ,1%  ,1/A 1        FM_CPU_MSMI_CATERR_LVT3_N
                                  2        FM_CPU_MSMI_CATERR_LVT3_PLD_N
R271             Q_RES_0402LF-0,5%,1/16W,CHIP,CA 1        RST_BMC_SELF_HW         
                                  2        RST_BMC_SELF_HW_R2      
R272             Q_RES_0402LF-0,5%,1/16W,CHIP,CA 1        SMB_BMC_MM15_SCL        
                                  2        SMB_BMC_MM15_R3_SCL     
R274             Q_RES_0402LF-100K,1%,1/16W,EMPB 1        P3V3_AUX                
                                  2        DEBUG_PORT_UART_RX      
R275             Q_RES_0402LF-0,5%,1/16W,CHIP,CA 1        PWRGD_P1V8_AUX          
                                  2        PWRGD_P1V8_AUX_R        
R276             Q_RES_0402LF-0,5%,1/16W,CHIP,CA 1        PWRGD_P1V2_AUX_R        
                                  2        PWRGD_P1V2_AUX          
R277             Q_RES_0402LF-0,5%,1/16W,CHIP,CA 1        PWRGD_P1V0_AUX_R        
                                  2        PWRGD_P1V0_AUX          
R278             Q_RES_0402LF-0,5%,1/16W,EMPTY,A 1        P1V2_AUX                
                                  2        P1V2_P1V0_I3C_VDDL1     
R279             Q_RES_0402LF-0,5%,1/16W,CHIP,CA 1        P1V0_AUX                
                                  2        P1V2_P1V0_I3C_VDDL1     
R280             Q_RES_0402LF-0,5%,1/16W,EMPTY,A 1        P1V2_AUX                
                                  2        P1V2_P1V0_I3C_VDDL2     
R281             Q_RES_0402LF-0,5%,1/16W,CHIP,CA 1        P1V0_AUX                
                                  2        P1V2_P1V0_I3C_VDDL2     
R282             Q_RES_0402LF-0,5%,1/16W,CHIP,CA 1        RST_BMC_HW              
                                  2        RST_BMC_SELF_HW_R3      
R283             Q_RES_0402LF-1.5K,1%,1/16W,EMPA 1        P3V3_AUX_DVDD           
                                  2        RGMII_BMC_MDC_R         
R284             Q_RES_0402LF-4.7K,1%,1/16W,EMPA 1        P3V3_AUX_DVDD           
                                  2        RST_RSTB_N              
R285             Q_RES_0402LF-1.5K,1%,1/16W,CHIA 1        P3V3_AUX_DVDD           
                                  2        RGMII_BMC_MDIO_R        
R286             Q_RES_0402LF-22,1%,1/16W,CHIP,A 1        XTAL_PHY_XI_R           
                                  2        XTAL_PHY_XI             
R287             Q_RES_0402LF-499,1%,1/16W,CHIPA 1        P3V3_AUX                
                                  2        RST_BMC_EXTRST_R2_N     
R288             Q_RES_0402LF-22,1%,1/16W,CHIP,A 1        XTAL_PHY_XO_R           
                                  2        XTAL_PHY_XO             
R289             Q_RES_0402LF-10K,1%,1/16W,CHIPA 1        P3V3_AUX                
                                  2        BJT_Q3_C                
R290             Q_RES_0402LF-47K,1%,1/16W,CHIPA 1        BJT_Q3_B                
                                  2        RST_BMC_EXTRST_R1_N     
R291             Q_RES_0402LF-4.7K,1%,1/16W,CHIA 1        P3V3_AUX                
                                  2        RST_BMC_EXTRST_R1_N     
R292             Q_RES_0402LF-0,5%,1/16W,CHIP,CA 1        PWRGD_P5V_AUX_R         
                                  2        PWRGD_P5V_AUX           
R293             Q_RES_0402LF-0,5%,1/16W,CHIP,CA 1        PWRGD_P3V3_AUX_R        
                                  2        PWRGD_P3V3_AUX          
R294             Q_RES_0402LF-0,5%,1/16W,CHIP,CA 1        SMB_BMC_MM16_SDA        
                                  2        SMB_BMC_MM16_R1_SDA     
R295             Q_RES_0402LF-10K,1%,1/16W,EMPTA 1        P3V3_AUX                
                                  2        DEBUG_PORT_PRSNT_BUF_EN 
R296             Q_RES_0402LF-100K,1%,1/16W,EMPB 1        DEBUG_PORT_PRSNT_BUF_EN 
                                  2        GND                     
R297             Q_RES_0402LF-0,5%,1/16W,CHIP,CA 1        RGMII_BMC_RX_CLK        
                                  2        RGMII_BMC_RX_CLK_R      
R298             Q_RES_0402LF-4.7K,1%,1/16W,CHIA 1        P3V3_AUX                
                                  2        SMB_DEBUG_AUX_LVC3_USB_R1_SCL
R299             Q_RES_0402LF-4.7K,1%,1/16W,CHIA 1        P3V3_AUX                
                                  2        SMB_DEBUG_AUX_LVC3_USB_R1_SDA
R300             Q_RES_0402LF-0,5%,1/16W,CHIP,CA 1        SMB_DEBUG_AUX_LVC3_USB_R1_SCL
                                  2        SMB_DEBUG_AUX_LVC3_USB_SCL
R301             Q_RES_0402LF-0,5%,1/16W,EMPTY,A 1        P3V3_AUX_RJ45           
                                  2        PU_RJ45_ESD             
R302             Q_RES_0402LF-0,5%,1/16W,CHIP,CA 1        SMB_DEBUG_AUX_LVC3_USB_R1_SDA
                                  2        SMB_DEBUG_AUX_LVC3_USB_SDA
R303             Q_RES_0402LF-0,5%,1/16W,CHIP,CA 1        SMB_BMC_MM15_SDA        
                                  2        SMB_BMC_MM15_R3_SDA     
R304             Q_RES_0402LF-220,5%,1/16W,CHIPA 1        PHY_LED3                
                                  2        LED3_AD0_ACT            
R305             Q_RES_0402LF-220,5%,1/16W,CHIPA 1        PHY_LED1                
                                  2        LED1_AD1_100M           
R306             Q_RES_0402LF-220,5%,1/16W,CHIPA 1        PHY_LED2                
                                  2        LED2_RXDELAY_1G         
R307             Q_RES_0402LF-4.7K,1%,1/16W,CHIA 1        P3V3_AUX_DVDD           
                                  2        PHY_LED1                
R308             Q_RES_0402LF-4.7K,1%,1/16W,EMPA 1        PHY_LED1                
                                  2        GND                     
R309             Q_RES_0402LF-4.7K,1%,1/16W,CHIA 1        P3V3_AUX_DVDD           
                                  2        PHY_LED2                
R310             Q_RES_0402LF-4.7K,1%,1/16W,EMPA 1        PHY_LED2                
                                  2        GND                     
R311             Q_RES_0402LF-4.7K,1%,1/16W,CHIA 1        P3V3_AUX_DVDD           
                                  2        PHY_LED3                
R312             Q_RES_0402LF-4.7K,1%,1/16W,EMPA 1        PHY_LED3                
                                  2        GND                     
R313             Q_RES_0402LF-470K,1%,1/16W,CHIA 1        RST_BMC_SELF_HW_D       
                                  2        GND                     
R314             Q_RES_0402LF-100K,1%,1/16W,CHIB 1        RST_BMC_SELF_HW_D_C     
                                  2        GND                     
R315             Q_RES_0402LF-0,5%,1/16W,CHIP,CA 1        RST_BMC_SRST_BUF_R_N    
                                  2        RST_BMC_SRST_BUF_R1_N   
R316             Q_RES_0402LF-0,5%,1/16W,CHIP,CA 1        BMC_PWR_LED             
                                  2        PWR_LED                 
R317             Q_RES_0402LF-0,5%,1/16W,CHIP,CA 1        PWR_LED_CPLD            
                                  2        PWR_LED                 
R318             Q_RES_0402LF-0,5%,1/16W,CHIP,CA 1        PWRGD_P3V3_AUX_R1       
                                  2        PWRGD_P3V3_AUX          
R319             Q_RES_0402LF-0,5%,1/16W,CHIP,CA 1        P3V3_AUX_DVDD           
                                  2        PU_LED_ACT              
R320             Q_RES_0402LF-0,5%,1/16W,CHIP,CA 1        PWRGD_P2V5_AUX_R1       
                                  2        PWRGD_P2V5_AUX          
R321             Q_RES_0402LF-0,5%,1/16W,CHIP,CA 1        PWRGD_P1V8_AUX_R1       
                                  2        PWRGD_P1V8_AUX          
R322             Q_RES_0402LF-0,5%,1/16W,CHIP,CA 1        PWRGD_P3V3_RGM_R1       
                                  2        PWRGD_P3V3_RGM          
R323             Q_RES_0402LF-0,5%,1/16W,CHIP,CA 1        PWRGD_P1V2_AUX_R1       
                                  2        PWRGD_P1V2_AUX          
R324             Q_RES_0402LF-1K,1%,1/16W,CHIP,A 1        P1V2_AUX                
                                  2        P0V6_DDR_VREF_AUX       
R325             Q_RES_0402LF-1K,1%,1/16W,CHIP,A 1        P0V6_DDR_VREF_AUX       
                                  2        GND                     
R326             Q_RES_0402LF-120,1%,1/16W,CHIPA 1        GND                     
                                  2        M_BMC_DDR4_MA<0>        
R327             Q_RES_0402LF-120,1%,1/16W,CHIPA 1        GND                     
                                  2        M_BMC_DDR4_MA<1>        
R328             Q_RES_0402LF-120,1%,1/16W,CHIPA 1        GND                     
                                  2        M_BMC_DDR4_MA<2>        
R329             Q_RES_0402LF-120,1%,1/16W,CHIPA 1        GND                     
                                  2        M_BMC_DDR4_MA<3>        
R330             Q_RES_0402LF-120,1%,1/16W,CHIPA 1        GND                     
                                  2        M_BMC_DDR4_MA<4>        
R331             Q_RES_0402LF-120,1%,1/16W,CHIPA 1        GND                     
                                  2        M_BMC_DDR4_MA<5>        
R332             Q_RES_0402LF-120,1%,1/16W,CHIPA 1        GND                     
                                  2        M_BMC_DDR4_MA<6>        
R333             Q_RES_0402LF-120,1%,1/16W,CHIPA 1        GND                     
                                  2        M_BMC_DDR4_MA<7>        
R334             Q_RES_0402LF-120,1%,1/16W,CHIPA 1        GND                     
                                  2        M_BMC_DDR4_MA<8>        
R335             Q_RES_0402LF-120,1%,1/16W,CHIPA 1        GND                     
                                  2        M_BMC_DDR4_MA<9>        
R336             Q_RES_0402LF-120,1%,1/16W,CHIPA 1        GND                     
                                  2        M_BMC_DDR4_MA<10>       
R337             Q_RES_0402LF-120,1%,1/16W,CHIPA 1        GND                     
                                  2        M_BMC_DDR4_MA<11>       
R338             Q_RES_0402LF-120,1%,1/16W,CHIPA 1        GND                     
                                  2        M_BMC_DDR4_MA<12>       
R339             Q_RES_0402LF-120,1%,1/16W,CHIPA 1        GND                     
                                  2        M_BMC_DDR4_MA<13>       
R340             Q_RES_0402LF-120,1%,1/16W,CHIPA 1        GND                     
                                  2        M_BMC_DDR4_MWE_N        
R341             Q_RES_0402LF-120,1%,1/16W,CHIPA 1        GND                     
                                  2        M_BMC_DDR4_MCAS_N       
R342             Q_RES_0402LF-120,1%,1/16W,CHIPA 1        GND                     
                                  2        M_BMC_DDR4_MRAS_N       
R343             Q_RES_0402LF-120,1%,1/16W,CHIPA 1        GND                     
                                  2        M_BMC_DDR4_MCS_N        
R344             Q_RES_0402LF-120,1%,1/16W,CHIPA 1        GND                     
                                  2        M_BMC_DDR4_MACT_N       
R345             Q_RES_0402LF-120,1%,1/16W,CHIPA 1        GND                     
                                  2        M_BMC_DDR4_MBG0         
R346             Q_RES_0402LF-120,1%,1/16W,CHIPA 1        GND                     
                                  2        M_BMC_DDR4_MBA0         
R347             Q_RES_0402LF-120,1%,1/16W,CHIPA 1        GND                     
                                  2        M_BMC_DDR4_MBA1         
R348             Q_RES_0402LF-120,1%,1/16W,CHIPA 1        GND                     
                                  2        M_BMC_DDR4_MODT         
R349             Q_RES_0402LF-120,1%,1/16W,CHIPA 1        GND                     
                                  2        M_BMC_DDR4_MCKE         
R350             Q_RES_0402LF-120,1%,1/16W,EMPTA 1        GND                     
                                  2        M_BMC_DDR4_MBG1         
R351             Q_RES_0402LF-120,1%,1/16W,CHIPA 1        M_BMC_DDR4_MA<0>        
                                  2        P1V2_AUX                
R352             Q_RES_0402LF-120,1%,1/16W,CHIPA 1        M_BMC_DDR4_MA<1>        
                                  2        P1V2_AUX                
R353             Q_RES_0402LF-120,1%,1/16W,CHIPA 1        M_BMC_DDR4_MA<2>        
                                  2        P1V2_AUX                
R354             Q_RES_0402LF-120,1%,1/16W,CHIPA 1        M_BMC_DDR4_MA<3>        
                                  2        P1V2_AUX                
R355             Q_RES_0402LF-120,1%,1/16W,CHIPA 1        M_BMC_DDR4_MA<4>        
                                  2        P1V2_AUX                
R356             Q_RES_0402LF-120,1%,1/16W,CHIPA 1        M_BMC_DDR4_MA<5>        
                                  2        P1V2_AUX                
R357             Q_RES_0402LF-120,1%,1/16W,CHIPA 1        M_BMC_DDR4_MA<6>        
                                  2        P1V2_AUX                
R358             Q_RES_0402LF-120,1%,1/16W,CHIPA 1        M_BMC_DDR4_MA<7>        
                                  2        P1V2_AUX                
R359             Q_RES_0402LF-120,1%,1/16W,CHIPA 1        M_BMC_DDR4_MA<8>        
                                  2        P1V2_AUX                
R360             Q_RES_0402LF-120,1%,1/16W,CHIPA 1        M_BMC_DDR4_MA<9>        
                                  2        P1V2_AUX                
R361             Q_RES_0402LF-120,1%,1/16W,CHIPA 1        M_BMC_DDR4_MA<10>       
                                  2        P1V2_AUX                
R362             Q_RES_0402LF-120,1%,1/16W,CHIPA 1        M_BMC_DDR4_MA<11>       
                                  2        P1V2_AUX                
R363             Q_RES_0402LF-120,1%,1/16W,CHIPA 1        M_BMC_DDR4_MA<12>       
                                  2        P1V2_AUX                
R364             Q_RES_0402LF-120,1%,1/16W,CHIPA 1        M_BMC_DDR4_MA<13>       
                                  2        P1V2_AUX                
R365             Q_RES_0402LF-120,1%,1/16W,CHIPA 1        M_BMC_DDR4_MWE_N        
                                  2        P1V2_AUX                
R366             Q_RES_0402LF-120,1%,1/16W,CHIPA 1        M_BMC_DDR4_MCAS_N       
                                  2        P1V2_AUX                
R367             Q_RES_0402LF-120,1%,1/16W,CHIPA 1        M_BMC_DDR4_MRAS_N       
                                  2        P1V2_AUX                
R368             Q_RES_0402LF-120,1%,1/16W,CHIPA 1        M_BMC_DDR4_MCS_N        
                                  2        P1V2_AUX                
R369             Q_RES_0402LF-120,1%,1/16W,CHIPA 1        M_BMC_DDR4_MACT_N       
                                  2        P1V2_AUX                
R370             Q_RES_0402LF-120,1%,1/16W,CHIPA 1        M_BMC_DDR4_MBG0         
                                  2        P1V2_AUX                
R371             Q_RES_0402LF-120,1%,1/16W,CHIPA 1        M_BMC_DDR4_MBA0         
                                  2        P1V2_AUX                
R372             Q_RES_0402LF-120,1%,1/16W,CHIPA 1        M_BMC_DDR4_MBA1         
                                  2        P1V2_AUX                
R373             Q_RES_0402LF-120,1%,1/16W,CHIPA 1        M_BMC_DDR4_MODT         
                                  2        P1V2_AUX                
R374             Q_RES_0402LF-120,1%,1/16W,CHIPA 1        M_BMC_DDR4_MCKE         
                                  2        P1V2_AUX                
R375             Q_RES_0402LF-120,1%,1/16W,EMPTA 1        M_BMC_DDR4_MBG1         
                                  2        P1V2_AUX                
R376             Q_RES_0402LF-4.7K,1%,1/16W,CHIA 1        P5V_AUX                 
                                  2        USB_OC0_EN              
R377             Q_RES_0402LF-10K,1%,1/16W,EMPTB 1        USB_OC0_EN              
                                  2        GND                     
R378             Q_RES_0402LF-20K,1%,1/16W,CHIPA 1        USB_OC0_ILIM            
                                  2        GND                     
R379             Q_RES_0402LF-0,5%,1/16W,CHIP,CA 1        PWRGD_P1V0_AUX_R1       
                                  2        PWRGD_P1V0_AUX          
R380             Q_RES_0402LF-0,5%,1/16W,CHIP,CA 1        PWRGD_P1V8_AUX          
                                  2        PWRGD_P1V8_AUX_R2       
R381             Q_RES_0402LF-0,5%,1/16W,CHIP,CA 1        PWRGD_P5V_AUX           
                                  2        PWRGD_P5V_AUX_R2        
R382             Q_RES_0402LF-0,5%,1/16W,CHIP,CA 1        PWRGD_P3V3_AUX          
                                  2        PWRGD_P3V3_AUX_R2       
R383             Q_RES_0402LF-10K,1%,1/16W,CHIPA 1        P3V3_AUX                
                                  2        USB_OC0_REAR_N          
R384             Q_RES_0402LF-0,5%,1/16W,CHIP,CA 1        USB_OC0_REAR_N          
                                  2        USB_OC0_REAR_R_N        
R385             Q_RES_0402LF-0,5%,1/16W,CHIP,CA 1        USB_FPNL_DN             
                                  2        USB2_01_F_DN            
R386             Q_RES_0402LF-0,5%,1/16W,CHIP,CA 1        USB_FPNL_DP             
                                  2        USB2_01_F_DP            
R387             Q_RES_0402LF-4.7K,1%,1/16W,CHIA 1        P3V3_AUX                
                                  2        LOADSW_VBIAS            
R388             Q_RES_0402LF-4.7K,1%,1/16W,EMPA 1        LOADSW_VBIAS            
                                  2        GND                     
R389             Q_RES_0402LF-4.7K,1%,1/16W,CHIA 1        P3V3_AUX                
                                  2        PU_LOADSW_EN            
R390             Q_RES_0402LF-4.7K,1%,1/16W,EMPA 1        PU_LOADSW_EN            
                                  2        GND                     
R391             Q_RES_0402LF-100K,1%,1/16W,CHIA 1        DP_BMC_HPD_3V3          
                                  2        GND                     
R392             Q_RES_0402LF-100K,1%,1/16W,CHIA 1        DP_BMC_AUX_C_P          
                                  2        GND                     
R393             Q_RES_0402LF-0,5%,1/16W,CHIP,CA 1        PWRGD_P2V5_AUX          
                                  2        PWRGD_P2V5_AUX_R2       
R394             Q_RES_0402LF-33       ,1%  ,1/A 1        SMB_BMC_MM2_R_SDA       
                                  2        SMB_BMC_MM2_SDA         
R395             Q_RES_0402LF-1M,1%,1/16W,CHIP,A 1        DP_CONFIG1              
                                  2        GND                     
R396             Q_RES_0402LF-1M,1%,1/16W,CHIP,A 1        DP_CONFIG2              
                                  2        GND                     
R397             Q_RES_0402LF-0,5%,1/16W,CHIP,CA 1        SPA_SIN_SW_MNUSB        
                                  2        SPA_SIN_SW_MNUSB_R      
R398             Q_RES_0402LF-10K,1%,1/16W,CHIPA 1        P3V3_PL2303             
                                  2        SPA_SIN_SW_MNUSB_R      
R399             Q_RES_0402LF-0,5%,1/16W,CHIP,CA 1        PWRGD_P1V2_AUX          
                                  2        PWRGD_P1V2_AUX_R2       
R400             Q_RES_0402LF-1.24K,1%,1/16W,CHA 1        PHY_RDAC                
                                  2        GND                     
R401             Q_RES_0201LF-1.5K,1%,1/20W,CHIA 1        P3V3_PL2303             
                                  2        USB2_PL2303_EXT_DP      
R402             Q_RES_0201LF-27.4,1%,1/20W,CHIA 1        USB2_PL2303_EXT_DN      
                                  2        USB2_EXT_DN             
R403             Q_RES_0201LF-27.4,1%,1/20W,CHIA 1        USB2_PL2303_EXT_DP      
                                  2        USB2_EXT_DP             
R404             Q_RES_0402LF-33       ,1%  ,1/A 1        FM_RISER1_JTAG_SEL_R_N  
                                  2        FM_RISER1_JTAG_SEL_N    
R405             Q_RES_0402LF-33       ,1%  ,1/A 1        PD_BIOS_MUX_EN_R_N      
                                  2        PD_BIOS_MUX_EN_N        
R406             Q_RES_0402LF-0,5%,1/16W,CHIP,CA 1        P5V_BUS                 
                                  2        P5V_AUX_VBUS            
R407             Q_RES_0402LF-4.7K,5%,1/16W,CHIA 1        P3V3_AUX                
                                  2        SMB_BMC_ALERT15_R_N     
R408             Q_RES_0402LF-33       ,1%  ,1/A 1        SMB_BMC_ALERT15_N       
                                  2        SMB_BMC_ALERT15_R_N     
R409             Q_RES_0402LF-33       ,1%  ,1/A 1        SMB_BMC_MM15_SDA        
                                  2        SMB_BMC_MM15_R1_SDA     
R410             Q_RES_0402LF-33       ,1%  ,1/A 1        SMB_BMC_MM15_SCL        
                                  2        SMB_BMC_MM15_R1_SCL     
R411             Q_RES_0402LF-100,1%,1/16W,EMPTA 1        FRU_E0                  
                                  2        GND                     
R412             Q_RES_0402LF-100,1%,1/16W,CHIPA 1        FRU_E1                  
                                  2        GND                     
R413             Q_RES_0402LF-100,1%,1/16W,CHIPA 1        FRU_E2                  
                                  2        GND                     
R414             Q_RES_0402LF-4.7K,5%,1/16W,EMPA 1        P3V3_AUX                
                                  2        TEMP_A2                 
R415             Q_RES_0402LF-100,1%,1/16W,CHIPA 1        TEMP_A2                 
                                  2        GND                     
R416             Q_RES_0402LF-4.7K,5%,1/16W,CHIA 1        P3V3_AUX                
                                  2        TEMP_A1                 
R417             Q_RES_0402LF-100,1%,1/16W,EMPTA 1        TEMP_A1                 
                                  2        GND                     
R418             Q_RES_0402LF-4.7K,5%,1/16W,EMPA 1        P3V3_AUX                
                                  2        TEMP_A0                 
R419             Q_RES_0402LF-100,1%,1/16W,CHIPA 1        TEMP_A0                 
                                  2        GND                     
R420             Q_RES_0402LF-33       ,1%  ,1/A 1        SMB_BMC_MM15_R2_SCL     
                                  2        SMB_BMC_MM15_SCL        
R421             Q_RES_0402LF-33       ,1%  ,1/A 1        SMB_BMC_MM15_R2_SDA     
                                  2        SMB_BMC_MM15_SDA        
R422             Q_RES_0402LF-4.7K,5%,1/16W,CHIA 1        P3V3_AUX                
                                  2        SMB_BMC_MM13_SCL        
R423             Q_RES_0402LF-33       ,1%  ,1/A 1        SMB_BMC_MM13_R_SCL      
                                  2        SMB_BMC_MM13_SCL        
R424             Q_RES_0402LF-33       ,1%  ,1/A 1        SMB_BMC_MM13_R_SDA      
                                  2        SMB_BMC_MM13_SDA        
R425             Q_RES_0402LF-33       ,1%  ,1/A 1        SMB_BMC_MM14_R_SCL      
                                  2        SMB_BMC_MM14_SCL        
R426             Q_RES_0402LF-33       ,1%  ,1/A 1        SMB_BMC_MM14_R_SDA      
                                  2        SMB_BMC_MM14_SDA        
R427             Q_RES_0402LF-33       ,1%  ,1/A 1        UART_BMC_1_RXD_R        
                                  2        UART_BMC_1_RXD          
R428             Q_RES_0402LF-4.7K,5%,1/16W,CHIA 1        P3V3_AUX                
                                  2        SMB_BMC_MM13_SDA        
R429             Q_RES_0402LF-4.7K,5%,1/16W,CHIA 1        P3V3_AUX                
                                  2        SMB_BMC_MM14_SCL        
R430             Q_RES_0402LF-4.7K,5%,1/16W,CHIA 1        P3V3_AUX                
                                  2        FM_BMC_ONCTL_R_N        
R431             Q_RES_0402LF-100,1%,1/16W,CHIPA 1        PD_BMC_DISABLE          
                                  2        GND                     
R432             Q_RES_0402LF-0,5%,1/16W,EMPTY,A 1        FM_PWR_R_BTN            
                                  2        FM_PWR_BTN              
R433             Q_RES_0402LF-33       ,1%  ,1/A 1        SGPIO_DI_1              
                                  2        SGPIO_BMC_M1_DI         
R434             Q_RES_0402LF-33       ,1%  ,1/A 1        SGPIO_CLK_PLD_0         
                                  2        SGPIO_CLK_0             
R435             Q_RES_0402LF-33       ,1%  ,1/A 1        SGPIO_PLD_DO_0          
                                  2        SGPIO_DO_0              
R436             Q_RES_0402LF-33       ,1%  ,1/A 1        SGPIO_PLD_LD_0          
                                  2        SGPIO_LD_0              
R437             Q_RES_0402LF-33       ,1%  ,1/A 1        SGPIO_PLD_DI_0          
                                  2        SGPIO_DI_0              
R438             Q_RES_0402LF-4.7K,5%,1/16W,CHIA 1        P3V3_AUX                
                                  2        SMB_BMC_MM14_SDA        
R439             Q_RES_0402LF-33       ,1%  ,1/A 1        FM_PECI_SEL_N           
                                  2        FM_PECI_SEL_R_N         
R440             Q_RES_0402LF-33       ,1%  ,1/A 1        FM_INTRUDER_HDR_PCH_R_N 
                                  2        FM_INTRUDER_HDR_PCH_N   
R441             Q_RES_0402LF-4.7K,5%,1/16W,CHIA 1        P3V3_AUX                
                                  2        FM_INTRUDER_HDR_PCH_R_N 
R442             Q_RES_0402LF-33       ,1%  ,1/A 1        SMB_BMC_ALERT3_N        
                                  2        SMB_BMC_ALERT3_R_N      
R443             Q_RES_0402LF-33       ,1%  ,1/A 1        SMB_BMC_ALERT4_N        
                                  2        SMB_BMC_ALERT4_R_N      
R444             Q_RES_0402LF-33       ,1%  ,1/A 1        FM_ESPI_PLD_EN          
                                  2        FM_ESPI_PLD_R1_EN       
R446             Q_RES_0402LF-4.7K,5%,1/16W,CHIA 1        P3V3_AUX                
                                  2        FM_PECI_SEL_N           
R447             Q_RES_0402LF-0,5%,1/16W,CHIP,CA 1        RST_EXTRST_N            
                                  2        RST_EXTRST_R_N          
R448             Q_RES_0402LF-33       ,1%  ,1/A 1        SMB_BMC_ALERT9_N        
                                  2        SMB_BMC_ALERT9_R_N      
R449             Q_RES_0402LF-33       ,1%  ,1/A 1        SMB_BMC_ALERT10_N       
                                  2        SMB_BMC_ALERT10_R_N     
R450             Q_RES_0402LF-0,5%,1/16W,EMPTY,A 1        RST_BMC_SELF_HW         
                                  2        RST_BMC_SELF_HW_R3      
R451             Q_RES_0402LF-0,5%,1/16W,CHIP,CA 1        PWRGD_P1V0_AUX_DELAY    
                                  2        PWRGD_P1V0_AUX_DELAY_R1 
R452             Q_RES_0402LF-4.7K,5%,1/16W,CHIA 1        P3V3_AUX                
                                  2        RST_WDTRST_PLD_N        
R453             Q_RES_0402LF-0,5%,1/16W,CHIP,CA 1        SMB_BMC_ALERT3_N        
                                  2        SMB_BMC_ALERT3_R1_N     
R454             Q_RES_0402LF-0,5%,1/16W,CHIP,CA 1        SMB_BMC_ALERT4_N        
                                  2        SMB_BMC_ALERT4_R1_N     
R455             Q_RES_0402LF-4.7K,5%,1/16W,EMPA 1        P3V3_AUX                
                                  2        PHYA0                   
R456             Q_RES_0402LF-0,5%,1/16W,CHIP,CA 1        SMB_BMC_ALERT9_N        
                                  2        SMB_BMC_ALERT9_R1_N     
R457             Q_RES_0402LF-0,5%,1/16W,CHIP,CA 1        SMB_BMC_ALERT10_N       
                                  2        SMB_BMC_ALERT10_R1_N    
R458             Q_RES_0402LF-33       ,1%  ,1/A 1        BMC_CPLD_GPIO_3         
                                  2        BMC_CPLD_GPIO_3_R1      
R459             Q_RES_0402LF-33       ,1%  ,1/A 1        BMC_CPLD_GPIO_4         
                                  2        BMC_CPLD_GPIO_4_R1      
R460             Q_RES_0402LF-33       ,1%  ,1/A 1        BMC_CPLD_GPIO_5         
                                  2        BMC_CPLD_GPIO_5_R1      
R461             Q_RES_0402LF-33       ,1%  ,1/A 1        BMC_CPLD_GPIO_6         
                                  2        BMC_CPLD_GPIO_6_R1      
R462             Q_RES_0402LF-33       ,1%  ,1/A 1        BMC_CPLD_GPIO_14_R1     
                                  2        BMC_CPLD_GPIO_14        
R463             Q_RES_0402LF-33       ,1%  ,1/A 1        BMC_CPLD_GPIO_11_R1     
                                  2        BMC_CPLD_GPIO_11        
R464             Q_RES_0402LF-10K,1%,1/16W,CHIPA 1        P3V3_AUX                
                                  2        FM_TPM_PRSNT_0_N        
R465             Q_RES_0402LF-33       ,1%  ,1/A 1        BMC_CPLD_GPIO_12_R1     
                                  2        BMC_CPLD_GPIO_12        
R466             Q_RES_0402LF-33       ,1%  ,1/A 1        BMC_CPLD_GPIO_13_R1     
                                  2        BMC_CPLD_GPIO_13        
R467             Q_RES_0402LF-2K,1%,1/16W,CHIP,A 1        PD_BIOS_MUX_EN_N        
                                  2        GND                     
R468             Q_RES_0402LF-33       ,1%  ,1/A 1        BMC_CPLD_GPIO_7_R1      
                                  2        BMC_CPLD_GPIO_7         
R469             Q_RES_0402LF-33       ,1%  ,1/A 1        BMC_CPLD_GPIO_8_R1      
                                  2        BMC_CPLD_GPIO_8         
R470             Q_RES_0402LF-33       ,1%  ,1/A 1        RGMII_BMC_RXD_<2>       
                                  2        RGMII_BMC_R_RXD_<2>     
R471             Q_RES_0402LF-33       ,1%  ,1/A 1        RGMII_BMC_RXD_<3>       
                                  2        RGMII_BMC_R_RXD_<3>     
R472             Q_RES_0402LF-33       ,1%  ,1/A 1        BMC_CPLD_GPIO_9_R1      
                                  2        BMC_CPLD_GPIO_9         
R473             Q_RES_0402LF-33       ,1%  ,1/A 1        BMC_CPLD_GPIO_10_R1     
                                  2        BMC_CPLD_GPIO_10        
R474             Q_RES_0402LF-33       ,1%  ,1/A 1        BMC_CPLD_GPIO_15        
                                  2        BMC_CPLD_GPIO_15_R1     
R475             Q_RES_0402LF-33       ,1%  ,1/A 1        BMC_CPLD_GPIO_16        
                                  2        BMC_CPLD_GPIO_16_R1     
R476             Q_RES_0402LF-33       ,1%  ,1/A 1        BMC_CPLD_GPIO_17        
                                  2        BMC_CPLD_GPIO_17_R1     
R477             Q_RES_0402LF-33       ,1%  ,1/A 1        BMC_CPLD_GPIO_18        
                                  2        BMC_CPLD_GPIO_18_R1     
R478             Q_RES_0402LF-33       ,1%  ,1/A 1        BMC_CPLD_GPIO_19        
                                  2        BMC_CPLD_GPIO_19_R1     
R479             Q_RES_0402LF-33       ,1%  ,1/A 1        BMC_CPLD_GPIO_20        
                                  2        BMC_CPLD_GPIO_20_R1     
R480             Q_RES_0402LF-33       ,1%  ,1/A 1        BMC_CPLD_GPIO_21        
                                  2        BMC_CPLD_GPIO_21_R1     
R481             Q_RES_0402LF-33       ,1%  ,1/A 1        SPI_PCH_MUXED_CLK       
                                  2        SPI_PCH_CLK_FLASH_R1    
R482             Q_RES_0402LF-33       ,1%  ,1/A 1        SPI_PCH_MUXED_IO0       
                                  2        SPI_PCH_IO0_FLASH_R1    
R483             Q_RES_0402LF-33       ,1%  ,1/A 1        SPI_PCH_MUXED_IO2       
                                  2        SPI_PCH_IO2_FLASH_R1    
R484             Q_RES_0402LF-33       ,1%  ,1/A 1        SPI_PCH_MUXED_IO1       
                                  2        SPI_PCH_IO1_FLASH_R1    
R485             Q_RES_0402LF-33       ,1%  ,1/A 1        SPI_PCH_MUXED_CS0_N     
                                  2        SPI_PCH_CS0_FLASH_R1_N  
R486             Q_RES_0402LF-33       ,1%  ,1/A 1        SPI_PCH_MUXED_IO3       
                                  2        SPI_PCH_IO3_FLASH_R1    
R487             Q_RES_0402LF-4.7K,1%,1/16W,EMPA 1        SPI_PCH_CS0_FLASH_R1_N  
                                  2        GND                     
R488             Q_RES_0402LF-4.7K,1%,1/16W,CHIA 1        P3V3_AUX                
                                  2        SPI_PCH_IO2_FLASH_R1    
R489             Q_RES_0402LF-33       ,1%  ,1/A 1        BMC_CPLD_GPIO_22        
                                  2        BMC_CPLD_GPIO_22_R1     
R490             Q_RES_0402LF-4.7K,1%,1/16W,CHIA 1        P3V3_AUX                
                                  2        SPI_PCH_CS0_FLASH_R1_N  
R491             Q_RES_0402LF-33       ,1%  ,1/A 1        BMC_CPLD_GPIO_23        
                                  2        BMC_CPLD_GPIO_23_R1     
R492             Q_RES_0402LF-4.7K,1%,1/16W,CHIA 1        P3V3_AUX                
                                  2        SPI_PCH_IO3_FLASH_R1    
R493             Q_RES_0402LF-33       ,1%  ,1/A 1        BMC_CPLD_GPIO_24        
                                  2        BMC_CPLD_GPIO_24_R1     
R494             Q_RES_0402LF-33       ,1%  ,1/A 1        RST_BMC_SELF_HW_R1      
                                  2        RST_BMC_SELF_HW         
R495             Q_RES_0402LF-0,5%,1/16W,CHIP,CA 1        BMC_CPLD_GPIO_1         
                                  2        BMC_CPLD_GPIO_1_R2      
R496             Q_RES_0402LF-4.7K,1%,1/16W,EMPA 1        P3V3_AUX                
                                  2        RST_SPI_PCH_FLASH_R1_N  
R497             Q_RES_0402LF-10K,1%,1/16W,CHIPA 1        P3V3_AUX                
                                  2        IRQ_TPM_SPI_N           
R498             Q_RES_0402LF-0,5%,1/16W,CHIP,CA 1        SPI_SYS_R1_MOSI         
                                  2        SPI_SYS_R_MOSI          
R499             Q_RES_0402LF-0,5%,1/16W,CHIP,CA 1        SPI_SYS_R1_MISO         
                                  2        SPI_SYS_R_MISO          
R500             Q_RES_0402LF-0,5%,1/16W,CHIP,CA 1        SPI_TPM_CS_N_R          
                                  2        SPI_TPM_CS_R_N          
R501             Q_RES_0402LF-0,5%,1/16W,CHIP,CA 1        SPI_SYS_R1_CLK          
                                  2        SPI_SYS_R_CLK           
R502             Q_RES_0402LF-4.7K,1%,1/16W,CHIA 1        P3V3_AUX                
                                  2        FM_ID_LED_N             
R503             Q_RES_0402LF-0,5%,1/16W,CHIP,CA 1        RST_PLTRST_TPM_N        
                                  2        RST_PLTRST_N            
R504             Q_RES_0402LF-8.2K     ,5%  ,1/A 1        P3V3_AUX                
                                  2        REAR_ID_RST_BTN_N       
R505             Q_RES_0402LF-0,5%,1/16W,CHIP,CA 1        IRQ_TPM_SPI_N           
                                  2        IRQ_TPM_SPI_R_N         
R506             Q_RES_0402LF-100,1%,1/16W,CHIPA 1        PD_BMC_DEBUG            
                                  2        GND                     
R507             Q_RES_0402LF-100,1%,1/16W,CHIPA 1        PD_JTAGEN               
                                  2        GND                     
R508             Q_RES_0402LF-10K,1%,1/16W,CHIPA 1        P3V3_AUX                
                                  2        MB_JTAG_PLD_R_JTAGEN    
R509             Q_RES_0402LF-33       ,1%  ,1/A 1        MB_JTAG_PLD_R_JTAGEN    
                                  2        JTAG_SCM_PLD_JTAGEN     
R510             Q_RES_0402LF-33       ,1%  ,1/A 1        JTAG_SCM_TCK            
                                  2        JTAG_SCM_PLD_TCK        
R511             Q_RES_0402LF-33       ,1%  ,1/A 1        JTAG_SCM_TMS            
                                  2        JTAG_SCM_PLD_TMS        
R512             Q_RES_0402LF-33       ,1%  ,1/A 1        JTAG_SCM_TDI            
                                  2        JTAG_SCM_PLD_TDI        
R513             Q_RES_0402LF-33       ,1%  ,1/A 1        JTAG_SCM_TDO            
                                  2        JTAG_SCM_PLD_TDO        
R514             Q_RES_0402LF-33       ,1%  ,1/A 1        JTAG_SCM_PLD_TCK        
                                  2        JTAG_SCM_CONN_TCK       
R515             Q_RES_0402LF-33       ,1%  ,1/A 1        JTAG_SCM_PLD_TMS        
                                  2        JTAG_SCM_CONN_TMS       
R516             Q_RES_0402LF-33       ,1%  ,1/A 1        JTAG_SCM_PLD_TDI        
                                  2        JTAG_SCM_CONN_TDI       
R517             Q_RES_0402LF-33       ,1%  ,1/A 1        JTAG_SCM_PLD_TDO        
                                  2        JTAG_SCM_CONN_TDO       
R518             Q_RES_0402LF-33       ,1%  ,1/A 1        JTAG_SCM_PLD_R1_JTAGEN  
                                  2        JTAG_SCM_PLD_JTAGEN     
R519             Q_RES_0402LF-0,5%,1/16W,CHIP,CA 1        BMC_CPLD_GPIO_2         
                                  2        BMC_CPLD_GPIO_2_R2      
R520             Q_RES_0402LF-0,5%,1/16W,CHIP,CA 1        BMC_CPLD_GPIO_3         
                                  2        BMC_CPLD_GPIO_3_R2      
R521             Q_RES_0402LF-4.7K,5%,1/16W,CHIA 1        P3V3_AUX                
                                  2        SMB_BMC_MM10_SDA        
R522             Q_RES_0402LF-33       ,1%  ,1/A 1        BMC_CPLD_GPIO_4_R2      
                                  2        BMC_CPLD_GPIO_4         
R523             Q_RES_0402LF-10K,0.10%,1/16W,CA 1        P3V3_RGM                
                                  2        JTAG_SCM_TDO            
R524             Q_RES_0402LF-33       ,1%  ,1/A 1        BMC_CPLD_GPIO_5_R2      
                                  2        BMC_CPLD_GPIO_5         
R525             Q_RES_0402LF-33       ,1%  ,1/A 1        BMC_CPLD_GPIO_6_R2      
                                  2        BMC_CPLD_GPIO_6         
R526             Q_RES_0402LF-33       ,1%  ,1/A 1        BMC_CPLD_GPIO_7_R2      
                                  2        BMC_CPLD_GPIO_7         
R527             Q_RES_0402LF-0,5%,1/16W,CHIP,CA 1        USB_HOST_BMC_B_R_DP     
                                  2        USB_HOST_BMC_B_DP       
R528             Q_RES_0402LF-0,5%,1/16W,CHIP,CA 1        USB_HOST_BMC_B_R_DN     
                                  2        USB_HOST_BMC_B_DN       
R529             Q_RES_0402LF-0,5%,1/16W,EMPTY,A 1        SPI_SYS_R1_CLK          
R530             Q_RES_0402LF-0,5%,1/16W,EMPTY,A 1        SPI_SYS_R1_MOSI         
R531             Q_RES_0402LF-33       ,1%  ,1/A 1        BMC_CPLD_GPIO_8_R2      
                                  2        BMC_CPLD_GPIO_8         
R532             Q_RES_0402LF-33       ,1%  ,1/B 1        BMC_EMMC_DT0            
                                  2        EMMC_DT0_R              
R533             Q_RES_0402LF-33       ,1%  ,1/A 1        BMC_CPLD_GPIO_9_R2      
                                  2        BMC_CPLD_GPIO_9         
R534             Q_RES_0402LF-33       ,1%  ,1/A 1        BMC_CPLD_GPIO_10_R2     
                                  2        BMC_CPLD_GPIO_10        
R535             Q_RES_0402LF-33       ,1%  ,1/A 1        BMC_CPLD_GPIO_11_R2     
                                  2        BMC_CPLD_GPIO_11        
R536             Q_RES_0402LF-33       ,1%  ,1/A 1        BMC_CPLD_GPIO_12_R2     
                                  2        BMC_CPLD_GPIO_12        
R537             Q_RES_0402LF-33       ,1%  ,1/A 1        BMC_CPLD_GPIO_13_R2     
                                  2        BMC_CPLD_GPIO_13        
R538             Q_RES_0402LF-22,5%,1/16W,CHIP,A 1        RGMII_BMC_TX_R_CLK      
                                  2        RGMII_BMC_TX_CLK        
R539             Q_RES_0402LF-22,5%,1/16W,CHIP,A 1        RGMII_BMC_TX_R_CTRL     
                                  2        RGMII_BMC_TX_CTRL       
R540             Q_RES_0402LF-33       ,1%  ,1/A 1        BMC_CPLD_GPIO_14_R2     
                                  2        BMC_CPLD_GPIO_14        
R541             Q_RES_0402LF-33       ,1%  ,1/A 1        BMC_CPLD_GPIO_15_R2     
                                  2        BMC_CPLD_GPIO_15        
R542             Q_RES_0402LF-0,5%,1/16W,CHIP,CA 1        BMC_CPLD_GPIO_16        
                                  2        BMC_CPLD_GPIO_16_R2     
R543             Q_RES_0402LF-33       ,1%  ,1/A 1        SPI_BMC_BOOT_CLK        
                                  2        SPI_BMC_CLK_FLASH_R2    
R544             Q_RES_0402LF-33       ,1%  ,1/A 1        SPI_BMC_BOOT_MOSI       
                                  2        SPI_BMC_IO0_FLASH_R2    
R545             Q_RES_0402LF-33       ,1%  ,1/A 1        SPI_BMC_BOOT_IO2        
                                  2        SPI_BMC_IO2_FLASH_R2    
R546             Q_RES_0402LF-33       ,1%  ,1/A 1        SPI_BMC_BOOT_MISO       
                                  2        SPI_BMC_IO1_FLASH_R2    
R547             Q_RES_0402LF-33       ,1%  ,1/A 1        SPI_BMC_BOOT_CS1_R_N    
                                  2        SPI_BMC_CS1_FLASH_R2_N  
R548             Q_RES_0402LF-33       ,1%  ,1/A 1        SPI_BMC_BOOT_IO3        
                                  2        SPI_BMC_IO3_FLASH_R2    
R549             Q_RES_0402LF-33       ,1%  ,1/A 1        SPI_BMC_BOOT_CLK        
                                  2        SPI_BMC_CLK_FLASH_R1    
R550             Q_RES_0402LF-33       ,1%  ,1/A 1        SPI_BMC_BOOT_MOSI       
                                  2        SPI_BMC_IO0_FLASH_R1    
R551             Q_RES_0402LF-33       ,1%  ,1/A 1        SPI_BMC_BOOT_IO2        
                                  2        SPI_BMC_IO2_FLASH_R1    
R552             Q_RES_0402LF-33       ,1%  ,1/A 1        SPI_BMC_BOOT_MISO       
                                  2        SPI_BMC_IO1_FLASH_R1    
R553             Q_RES_0402LF-33       ,1%  ,1/A 1        SPI_BMC_BOOT_CS0_R_N    
                                  2        SPI_BMC_CS0_FLASH_R1_N  
R554             Q_RES_0402LF-33       ,1%  ,1/A 1        SPI_BMC_BOOT_IO3        
                                  2        SPI_BMC_IO3_FLASH_R1    
R555             Q_RES_0402LF-4.7K,1%,1/16W,CHIA 1        P3V3_AUX                
                                  2        SPI_BMC_IO2_FLASH_R1    
R556             Q_RES_0402LF-4.7K,1%,1/16W,EMPA 1        P3V3_AUX                
                                  2        SPI_BMC_IO2_FLASH_R2    
R557             Q_RES_0402LF-4.7K,1%,1/16W,CHIA 1        P3V3_AUX                
                                  2        SPI_BMC_CS0_FLASH_R1_N  
R558             Q_RES_0402LF-4.7K,1%,1/16W,EMPA 1        P3V3_AUX                
                                  2        SPI_BMC_CS1_FLASH_R2_N  
R559             Q_RES_0402LF-4.7K,1%,1/16W,CHIA 1        P3V3_RGM                
                                  2        SPI_BMC_IO3_FLASH_R1    
R560             Q_RES_0402LF-4.7K,1%,1/16W,EMPA 1        P3V3_RGM                
                                  2        SPI_BMC_IO3_FLASH_R2    
R561             Q_RES_0402LF-33       ,1%  ,1/B 1        RST_SPI_BMC_FLASH_R2_N  
                                  2        RST_SPI_FLASH_N         
R562             Q_RES_0402LF-33       ,1%  ,1/B 1        RST_SPI_BMC_FLASH_R1_N  
                                  2        RST_SPI_FLASH_N         
R563             Q_RES_0402LF-4.7K,1%,1/16W,CHIA 1        P3V3_AUX                
                                  2        RST_SPI_FLASH_N         
R564             Q_RES_0402LF-0,5%,1/16W,CHIP,CA 1        SYS_BMC_PWRBTN_R_N      
                                  2        SYS_PWRBTN_N            
R565             Q_RES_0402LF-0,5%,1/16W,CHIP,CA 1        ID_RST_BTN_BMC_R_N      
                                  2        ID_RST_BTN_BMC_N        
R566             Q_RES_0402LF-0,5%,1/16W,CHIP,CA 1        RST_BMC_RSTBTN_OUT_R_N  
                                  2        RST_BMC_RSTBTN_OUT_N    
R567             Q_RES_0402LF-33       ,1%  ,1/A 1        SMB_BMC_MM7_R_SCL       
                                  2        SMB_BMC_MM7_SCL         
R568             Q_RES_0402LF-1K,1%,1/16W,CHIP,A 1        P3V3_AUX                
                                  2        PWR_LED_P3V3_AUX        
R569             Q_RES_0402LF-1K,1%,1/16W,CHIP,A 1        P3V3_AUX                
                                  2        ID_LED_P3V3_AUX         
R570             Q_RES_0402LF-33       ,1%  ,1/A 1        SMB_BMC_MM7_R_SDA       
                                  2        SMB_BMC_MM7_SDA         
R571             Q_RES_0402LF-0,5%,1/16W,CHIP,CA 1        IRQ_BMC_PCH_NMI_N       
                                  2        IRQ_BMC_PCH_NMI_R_N     
R572             Q_RES_0402LF-0,5%,1/16W,CHIP,CA 1        BMC_CPLD_GPIO_17        
                                  2        BMC_CPLD_GPIO_17_R2     
R573             Q_RES_0402LF-0,5%,1/16W,CHIP,CA 1        BMC_CPLD_GPIO_18        
                                  2        BMC_CPLD_GPIO_18_R2     
R574             Q_RES_0402LF-0,5%,1/16W,CHIP,CA 1        BMC_CPLD_GPIO_19        
                                  2        BMC_CPLD_GPIO_19_R2     
R575             Q_RES_0402LF-0,5%,1/16W,CHIP,CA 1        BMC_CPLD_GPIO_20        
                                  2        BMC_CPLD_GPIO_20_R2     
R576             Q_RES_0402LF-0,5%,1/16W,CHIP,CA 1        BMC_CPLD_GPIO_21        
                                  2        BMC_CPLD_GPIO_21_R2     
R577             Q_RES_0402LF-0,5%,1/16W,CHIP,CA 1        BMC_CPLD_GPIO_22        
                                  2        BMC_CPLD_GPIO_22_R2     
R578             Q_RES_0402LF-0,5%,1/16W,CHIP,CA 1        BMC_CPLD_GPIO_23        
                                  2        BMC_CPLD_GPIO_23_R2     
R579             Q_RES_0402LF-0,5%,1/16W,CHIP,CA 1        BMC_CPLD_GPIO_24        
                                  2        BMC_CPLD_GPIO_24_R2     
R580             Q_RES_0402LF-33       ,1%  ,1/A 1        SMB_BMC_MM9_R_SCL       
                                  2        SMB_BMC_MM9_SCL         
R581             Q_RES_0402LF-4.7K,5%,1/16W,CHIA 1        P3V3_AUX                
                                  2        BMC_CPLD_GPIO_1         
R582             Q_RES_0402LF-33       ,1%  ,1/A 1        SMB_BMC_MM9_R_SDA       
                                  2        SMB_BMC_MM9_SDA         
R583             Q_RES_0402LF-33       ,1%  ,1/A 1        SMB_BMC_MM10_R_SCL      
                                  2        SMB_BMC_MM10_SCL        
R584             Q_RES_0402LF-33       ,1%  ,1/A 1        SMB_BMC_MM10_R_SDA      
                                  2        SMB_BMC_MM10_SDA        
R585             Q_RES_0402LF-0,5%,1/16W,EMPTY,A 1        SPI_SYS_R1_MISO         
R586             Q_RES_0402LF-4.7K,5%,1/16W,CHIA 1        P3V3_AUX                
                                  2        BMC_CPLD_GPIO_2         
R587             Q_RES_0402LF-4.7K,5%,1/16W,CHIA 1        P3V3_AUX                
                                  2        BMC_CPLD_GPIO_3         
R588             Q_RES_0402LF-4.7K,5%,1/16W,CHIA 1        P3V3_AUX                
                                  2        BMC_CPLD_GPIO_4         
R589             Q_RES_0402LF-33       ,1%  ,1/A 1        SMB_BMC_MM3_R_SCL       
                                  2        SMB_BMC_MM3_SCL         
R590             Q_RES_0402LF-33       ,1%  ,1/A 1        SMB_BMC_MM3_R_SDA       
                                  2        SMB_BMC_MM3_SDA         
R591             Q_RES_0402LF-4.7K,5%,1/16W,CHIA 1        P3V3_AUX                
                                  2        BMC_CPLD_GPIO_5         
R592             Q_RES_0402LF-4.7K,5%,1/16W,CHIA 1        P3V3_AUX                
                                  2        BMC_CPLD_GPIO_6         
R593             Q_RES_0402LF-4.7K,5%,1/16W,CHIA 1        P3V3_AUX                
                                  2        BMC_CPLD_GPIO_7         
R594             Q_RES_0402LF-33       ,1%  ,1/A 1        SPI_TPM_CS_N            
                                  2        SPI_TPM_CS_R_N          
R595             Q_RES_0402LF-4.7K,5%,1/16W,CHIA 1        P3V3_AUX                
                                  2        BMC_CPLD_GPIO_8         
R596             Q_RES_0402LF-4.7K,5%,1/16W,CHIA 1        P3V3_AUX                
                                  2        BMC_CPLD_GPIO_9         
R597             Q_RES_0402LF-750,1%,1/16W,CHIPA 1        P3V3_AUX                
                                  2        PU_LED_POSTCODE_7_N     
R598             Q_RES_0402LF-750,1%,1/16W,CHIPA 1        P3V3_AUX                
                                  2        PU_LED_POSTCODE_6_N     
R599             Q_RES_0402LF-750,1%,1/16W,CHIPA 1        P3V3_AUX                
                                  2        PU_LED_POSTCODE_5_N     
R600             Q_RES_0402LF-750,1%,1/16W,CHIPA 1        P3V3_AUX                
                                  2        PU_LED_POSTCODE_4_N     
R601             Q_RES_0402LF-750,1%,1/16W,CHIPA 1        P3V3_AUX                
                                  2        PU_LED_POSTCODE_3_N     
R602             Q_RES_0402LF-750,1%,1/16W,CHIPA 1        P3V3_AUX                
                                  2        PU_LED_POSTCODE_2_N     
R603             Q_RES_0402LF-750,1%,1/16W,CHIPA 1        P3V3_AUX                
                                  2        PU_LED_POSTCODE_1_N     
R604             Q_RES_0402LF-750,1%,1/16W,CHIPA 1        P3V3_AUX                
                                  2        PU_LED_POSTCODE_0_N     
R605             Q_RES_0402LF-4.7K,5%,1/16W,CHIA 1        P3V3_AUX                
                                  2        BMC_CPLD_GPIO_10        
R606             Q_RES_0402LF-4.7K,5%,1/16W,CHIA 1        P3V3_AUX                
                                  2        BMC_CPLD_GPIO_11        
R607             Q_RES_0402LF-4.7K,5%,1/16W,CHIA 1        P3V3_AUX                
                                  2        BMC_CPLD_GPIO_12        
R608             Q_RES_0402LF-4.7K,5%,1/16W,CHIA 1        P3V3_AUX                
                                  2        BMC_CPLD_GPIO_13        
R609             Q_RES_0402LF-4.7K,5%,1/16W,CHIA 1        P3V3_AUX                
                                  2        BMC_CPLD_GPIO_14        
R610             Q_RES_0402LF-4.7K,5%,1/16W,CHIA 1        P3V3_AUX                
                                  2        SMB_BMC_MM15_SCL        
R611             Q_RES_0402LF-4.7K,5%,1/16W,CHIA 1        P3V3_AUX                
                                  2        BMC_CPLD_GPIO_15        
R612             Q_RES_0402LF-4.7K,5%,1/16W,CHIA 1        P3V3_AUX                
                                  2        BMC_CPLD_GPIO_16        
R613             Q_RES_0402LF-4.7K,5%,1/16W,CHIA 1        P3V3_AUX                
                                  2        BMC_CPLD_GPIO_17        
R614             Q_RES_0402LF-100K,1%,1/16W,CHIA 1        RST_SRST_PLD_BMC_R_N    
                                  2        GND                     
R615             Q_RES_0402LF-4.7K,5%,1/16W,CHIA 1        P3V3_AUX                
                                  2        PU_JTAG_TCK_MUX         
R616             Q_RES_0402LF-0,5%,1/16W,EMPTY,A 1        FM_JTAG_TCK_MUX_BMC_SEL_R
                                  2        FM_JTAG_TCK_MUX_BMC_SEL 
R617             Q_RES_0402LF-4.7K,5%,1/16W,CHIA 1        P3V3_AUX                
                                  2        BMC_CPLD_GPIO_18        
R618             Q_RES_0402LF-10K,1%,1/16W,CHIPA 1        GND                     
                                  2        FM_MB_STBY_EN           
R619             Q_RES_0402LF-4.7K,5%,1/16W,CHIA 1        P3V3_AUX                
                                  2        BMC_CPLD_GPIO_19        
R620             Q_RES_0402LF-100K,1%,1/16W,CHIA 1        FM_JTAG_TCK_MUX_BMC_SEL 
                                  2        GND                     
R621             Q_RES_0402LF-4.7K,5%,1/16W,CHIA 1        P3V3_AUX                
                                  2        BMC_CPLD_GPIO_20        
R622             Q_RES_0402LF-4.7K,5%,1/16W,CHIA 1        P3V3_AUX                
                                  2        BMC_CPLD_GPIO_21        
R623             Q_RES_0402LF-4.7K,1%,1/16W,CHIA 1        P3V3_RGM                
                                  2        RST_EXTRST_N            
R624             Q_RES_0402LF-4.7K,5%,1/16W,CHIA 1        P3V3_AUX                
                                  2        FM_BMC_DEBUG_SW_N       
R625             Q_RES_0402LF-4.7K,1%,1/16W,CHIA 1        P3V3_AUX                
                                  2        RST_RSMRST_N            
R626             Q_RES_0402LF-4.7K,5%,1/16W,CHIA 1        P3V3_AUX                
                                  2        BMC_CPLD_GPIO_22        
R627             Q_RES_0402LF-4.7K,5%,1/16W,CHIA 1        P3V3_AUX                
                                  2        BMC_CPLD_GPIO_23        
R628             Q_RES_0402LF-22,5%,1/16W,CHIP,A 1        RGMII_BMC_TXD_R_<0>     
                                  2        RGMII_BMC_TXD_<0>       
R629             Q_RES_0402LF-22,5%,1/16W,CHIP,A 1        RGMII_BMC_TXD_R_<1>     
                                  2        RGMII_BMC_TXD_<1>       
R630             Q_RES_0402LF-22,5%,1/16W,CHIP,A 1        RGMII_BMC_TXD_R_<2>     
                                  2        RGMII_BMC_TXD_<2>       
R631             Q_RES_0402LF-22,5%,1/16W,CHIP,A 1        RGMII_BMC_TXD_R_<3>     
                                  2        RGMII_BMC_TXD_<3>       
R632             Q_RES_0402LF-4.7K,5%,1/16W,CHIA 1        P3V3_AUX                
                                  2        BMC_CPLD_GPIO_24        
R633             Q_RES_0402LF-1K,1%,1/16W,EMPTYA 1        P3V3_AUX                
                                  2        RST_BMC_SELF_HW_R3      
R634             Q_RES_0402LF-0,5%,1/16W,CHIP,CA 1        BMC_CPLD_GPIO_25        
                                  2        BMC_CPLD_GPIO_25_R2     
R635             Q_RES_0402LF-33       ,1%  ,1/A 1        RST_WDTRST_PLD_N        
                                  2        RST_WDTRST_PLD_R2_N     
R636             Q_RES_0402LF-0,5%,1/16W,CHIP,CA 1        RST_EXTRST_N            
                                  2        RST_BMC_EXTRST_R2_N     
R637             Q_RES_0402LF-0,5%,1/16W,CHIP,CA 1        RST_WDTRST_PLD_R1_N     
                                  2        RST_WDTRST_PLD_N        
R638             Q_RES_0402LF-33       ,1%  ,1/A 1        RST_BMC_HW_R            
                                  2        RST_BMC_HW              
R639             Q_RES_0402LF-33       ,1%  ,1/A 1        JTAG_1_BMC_TDI_R        
                                  2        JTAG_MB_TDI             
R640             Q_RES_0402LF-4.7K,5%,1/16W,CHIA 1        P3V3_AUX                
                                  2        BMC_CPLD_GPIO_25        
R641             Q_RES_0402LF-4.7K,5%,1/16W,CHIA 1        P3V3_AUX                
                                  2        RST_BMC_SELF_HW_R2      
R647             Q_RES_0402LF-33       ,1%  ,1/B 1        BMC_EMMC_DT1            
                                  2        EMMC_DT1_R              
R648             Q_RES_0402LF-33       ,1%  ,1/B 1        BMC_EMMC_DT2            
                                  2        EMMC_DT2_R              
R649             Q_RES_0402LF-33       ,1%  ,1/B 1        BMC_EMMC_DT3            
                                  2        EMMC_DT3_R              
R650             Q_RES_0402LF-33       ,1%  ,1/B 1        BMC_EMMC_DT4            
                                  2        EMMC_DT4_R              
R651             Q_RES_0402LF-33       ,1%  ,1/B 1        BMC_EMMC_DT5            
                                  2        EMMC_DT5_R              
R652             Q_RES_0402LF-33       ,1%  ,1/B 1        BMC_EMMC_DT6            
                                  2        EMMC_DT6_R              
R653             Q_RES_0402LF-33       ,1%  ,1/B 1        BMC_EMMC_DT7            
                                  2        EMMC_DT7_R              
R654             Q_RES_0402LF-33       ,1%  ,1/B 1        BMC_EMMC_CLK            
                                  2        EMMC_CLK_R              
R655             Q_RES_0402LF-10K,1%,1/16W,EMPTA 1        P1V8_AUX                
                                  2        EMMC_DT0_R              
R656             Q_RES_0402LF-10K,1%,1/16W,EMPTA 1        P1V8_AUX                
                                  2        EMMC_DT1_R              
R657             Q_RES_0402LF-10K,1%,1/16W,EMPTA 1        P1V8_AUX                
                                  2        EMMC_DT2_R              
R658             Q_RES_0402LF-10K,1%,1/16W,EMPTA 1        P1V8_AUX                
                                  2        EMMC_DT3_R              
R659             Q_RES_0402LF-10K,1%,1/16W,EMPTA 1        P1V8_AUX                
                                  2        EMMC_DT4_R              
R660             Q_RES_0402LF-10K,1%,1/16W,EMPTA 1        P1V8_AUX                
                                  2        EMMC_DT5_R              
R661             Q_RES_0402LF-10K,1%,1/16W,EMPTA 1        P1V8_AUX                
                                  2        EMMC_DT6_R              
R662             Q_RES_0402LF-10K,1%,1/16W,EMPTA 1        P1V8_AUX                
                                  2        EMMC_DT7_R              
R663             Q_RES_0402LF-10K,1%,1/16W,EMPTA 1        P1V8_AUX                
                                  2        EMMC_CMD_R              
R677             Q_RES_0402LF-33       ,1%  ,1/B 1        QSPI_2_PLD_CS0_N        
                                  2        SPI_BMC_BOOT_CS0_R1_N   
R678             Q_RES_0402LF-33       ,1%  ,1/B 1        SPI_BMC_CLK_R           
                                  2        QSPI_2_PLD_CLK          
R679             Q_RES_0402LF-33       ,1%  ,1/B 1        SPI_BMC_MOSI_IO0_R      
                                  2        QSPI_2_PLD_IO0          
R680             Q_RES_0402LF-33       ,1%  ,1/B 1        SPI_BMC_MISO_IO1_R      
                                  2        QSPI_2_PLD_IO1          
R681             Q_RES_0402LF-33       ,1%  ,1/B 1        SPI_BMC_IO2_R           
                                  2        QSPI_2_PLD_IO2          
R682             Q_RES_0402LF-33       ,1%  ,1/B 1        SPI_BMC_IO3_R           
                                  2        QSPI_2_PLD_IO3          
R683             Q_RES_0402LF-4.7K,5%,1/16W,CHIA 1        P3V3_AUX                
                                  2        PU_SPI1WP_N             
R684             Q_RES_0402LF-1K,1%,1/16W,EMPTYA 1        BMC_EMMC_WP_N           
                                  2        GND                     
R685             Q_RES_0402LF-1K,1%,1/16W,EMPTYA 1        BMC_EMMC_CD_N           
                                  2        GND                     
R686             Q_RES_0402LF-4.7K,5%,1/16W,EMPA 1        P1V8_AUX                
                                  2        BMC_EMMC_WP_N           
R687             Q_RES_0402LF-4.7K,5%,1/16W,EMPA 1        P1V8_AUX                
                                  2        BMC_EMMC_CD_N           
R688             Q_RES_0402LF-33       ,1%  ,1/B 1        RST_SGPIO_RESET_N       
                                  2        RST_SGPIO_RESET_BMC_N   
R689             Q_RES_0402LF-33       ,1%  ,1/B 1        IRQ_SGPIO_N             
                                  2        IRQ_SGPIO_BMC_N         
R690             Q_RES_0402LF-33       ,1%  ,1/A 1        IRQ_SGPIO_R_N           
                                  2        IRQ_SGPIO_N             
R691             Q_RES_0402LF-33       ,1%  ,1/A 1        RST_SGPIO_RESET_R_N     
                                  2        RST_SGPIO_RESET_N       
R692             Q_RES_0402LF-4.7K,5%,1/16W,CHIA 1        P3V3_AUX                
                                  2        SMB_BMC_MM15_SDA        
R699             Q_RES_0402LF-4.7K,5%,1/16W,EMPA 1        P3V3_AUX                
                                  2        SPI_BMC_BOOT_CLK        
R704             Q_RES_0402LF-33       ,1%  ,1/A 1        RST_PCA9548_SENSOR_N    
                                  2        RST_PCA9548_SENSOR_R_N  
R705             Q_RES_0402LF-33       ,1%  ,1/A 1        FM_BMC_DBP_PRESENT_N    
                                  2        FM_BMC_DBP_PRESENT_R_N  
R706             Q_RES_0402LF-4.7K,5%,1/16W,CHIA 1        P3V3_AUX                
                                  2        FM_BMC_DBP_PRESENT_N    
R708             Q_RES_0402LF-0,5%,1/16W,CHIP,CA 1        PWRGD_P3V3_RGM          
                                  2        EN_P1V2_AUX             
R709             Q_RES_0402LF-10K,1%,1/16W,CHIPA 1        P3V3_RGM                
                                  2        PWRGD_P3V3_RGM_R        
R710             Q_RES_0402LF-100K,1%,1/16W,CHIA 1        P3V3_AUX                
                                  2        U43_CT                  
R711             Q_RES_0402LF-0,5%,1/16W,EMPTY,A 1        PWRGD_PSU_AC_PWROK      
                                  2        PWRGD_P1V0_AUX_DELAY    
R713             Q_RES_0402LF-33       ,1%  ,1/A 1        LPC_ESPI_SEL_R          
                                  2        LPC_ESPI_SEL            
R714             Q_RES_0402LF-2K,1%,1/16W,CHIP,A 1        LPC_ESPI_SEL            
                                  2        LPC_ESPI_SEL_R1         
R715             Q_RES_0402LF-10K,1%,1/16W,CHIPA 1        P5V_AUX                 
                                  2        LPC_ESPI_SEL_LV5        
R716             Q_RES_0402LF-10K,1%,1/16W,CHIPA 1        P3V3_AUX                
                                  2        LPC_ESPI_SEL_N          
R717             Q_RES_0402LF-4.7K,5%,1/16W,CHIA 1        P3V3_AUX                
                                  2        RST_BMC_RSTBTN_OUT_N    
R718             Q_RES_0402LF-33       ,1%  ,1/A 1        RST_PLTRST_N            
                                  2        RST_PLTRST_R1_N         
R724             Q_RES_0402LF-33       ,1%  ,1/A 1        SPI_BMC_BIOS_ROM_IO2    
                                  2        SPI_BMC_BIOS_ROM_R_IO2  
R725             Q_RES_0402LF-33       ,1%  ,1/A 1        SPI_BMC_BIOS_ROM_IO3    
                                  2        SPI_BMC_BIOS_ROM_R_IO3  
R728             Q_RES_0402LF-0,5%,1/16W,CHIP,CA 1        SPI_BMC_BIOS_CS0_N      
                                  2        SPI_BMC_BIOS_SOURCE_CS0_N
R759             Q_RES_0402LF-33       ,1%  ,1/A 1        UART_BMC_5_RXD          
                                  2        UART_BMC_5_RXD_R        
R760             Q_RES_0402LF-33       ,1%  ,1/A 1        UART_1_SCM_RXD          
                                  2        UART_1_SCM_R_RXD        
R761             Q_RES_0402LF-33       ,1%  ,1/A 1        UART_2_BMC_TXD          
                                  2        UART_2_BMC_R_TXD        
R762             Q_RES_0402LF-33       ,1%  ,1/A 1        UART_2_BMC_RXD          
                                  2        UART_2_BMC_R_RXD        
R763             Q_RES_0402LF-33       ,1%  ,1/A 1        FM_PCH_BMC_THERMTRIP_N  
                                  2        FM_PLT_BMC_THERMTRIP_N_R
R764             Q_RES_0402LF-0,5%,1/16W,EMPTY,A 1        PWRGD_P1V8_AUX          
                                  2        EN_P1V2_AUX             
R765             Q_RES_0402LF-33       ,1%  ,1/B 1        UART_BMC_5_TXD_R        
                                  2        UART_1_SCM_TXD          
R766             Q_RES_0402LF-33       ,1%  ,1/B 1        UART_BMC_5_RXD_R        
                                  2        UART_1_SCM_RXD          
R767             Q_RES_0402LF-33       ,1%  ,1/A 1        FM_TPM_PRSNT_0_N        
                                  2        FM_TPM_PRSNT_0_R_N      
R768             Q_RES_0402LF-8.2K     ,5%  ,1/A 1        P3V3_AUX                
                                  2        REAR_PWR_BTN_N          
R769             Q_RES_0402LF-33       ,1%  ,1/A 1        FM_THROTTLE_N           
                                  2        FM_THROTTLE_R_N         
R773             Q_RES_0402LF-33       ,1%  ,1/A 1        FM_SLPS3_GF_N           
                                  2        FM_SLPS3_GF_R_N         
R774             Q_RES_0402LF-4.7K,5%,1/16W,CHIA 1        P3V3_AUX                
                                  2        FM_SLPS3_GF_N           
R775             Q_RES_0402LF-1K,1%,1/16W,CHIP,A 1        BATTERY_DETECT          
                                  2        BATTERY_DETECT_R        
R776             Q_RES_0201LF-47K,1%,1/20W,CHIPA 1        BATTERY_DETECT_R        
                                  2        GND                     
R777             Q_RES_0402LF-200K,1%,1/16W,CHIA 1        P3V_BAT_R               
                                  2        P3V_BAT_R1              
R778             Q_RES_0402LF-100K,1%,1/16W,CHIA 1        P3V_BAT_SENSOR          
                                  2        GND                     
R779             Q_RES_0402LF-0,5%,1/16W,CHIP,CA 1        P2V5_AUX                
                                  2        ADCVREFEXT1             
R780             Q_RES_0402LF-0,5%,1/16W,EMPTY,A 1        P2V5_AUX                
                                  2        ADCVREFEXT0             
R781             Q_RES_0402LF-0,5%,1/16W,EMPTY,A 1        P1V8_AUX                
                                  2        ADCVREFEXT1             
R782             Q_RES_0402LF-0,5%,1/16W,EMPTY,A 1        P1V2_AUX                
                                  2        ADCVREFEXT1             
R783             Q_RES_0402LF-0,5%,1/16W,CHIP,CA 1        P1V8_AUX                
                                  2        ADCVREFEXT0             
R784             Q_RES_0402LF-0,5%,1/16W,EMPTY,A 1        P1V2_AUX                
                                  2        ADCVREFEXT0             
R785             Q_RES_0402LF-15.8K,1%,1/16W,CHA 1        P12V_AUX                
                                  2        P12V_SENSOR             
R786             Q_RES_0402LF-2K,1%,1/16W,CHIP,A 1        P12V_SENSOR             
                                  2        GND                     
R787             Q_RES_0402LF-5.36K,1%,1/16W,CHA 1        P5V_AUX                 
                                  2        P5V_SENSOR              
R788             Q_RES_0402LF-2K,1%,1/16W,CHIP,A 1        P5V_SENSOR              
                                  2        GND                     
R789             Q_RES_0402LF-2.87K,1%,1/16W,CHA 1        P3V3_AUX                
                                  2        P3V3_SENSOR             
R790             Q_RES_0402LF-2K,1%,1/16W,CHIP,A 1        P3V3_SENSOR             
                                  2        GND                     
R791             Q_RES_0402LF-1.69K,1%,1/16W,CHA 1        P2V5_AUX                
                                  2        P2V5_SENSOR             
R792             Q_RES_0402LF-2K,1%,1/16W,CHIP,A 1        P2V5_SENSOR             
                                  2        GND                     
R793             Q_RES_0402LF-665,1%,1/16W,CHIPA 1        P1V8_AUX                
                                  2        P1V8_SENSOR             
R794             Q_RES_0402LF-2K,1%,1/16W,CHIP,A 1        P1V8_SENSOR             
                                  2        GND                     
R795             Q_RES_0402LF-1K,1%,1/16W,CHIP,A 1        P1V2_AUX                
                                  2        P1V2_SENSOR             
R796             Q_RES_0402LF-1K,1%,1/16W,CHIP,A 1        P1V0_AUX                
                                  2        P1V0_SENSOR             
R797             Q_RES_0402LF-2.87K,1%,1/16W,CHA 1        PGPPA_BMC_AUX           
                                  2        PGPPA_BMC_AUX_SENSOR    
R798             Q_RES_0402LF-2K,1%,1/16W,CHIP,A 1        PGPPA_BMC_AUX_SENSOR    
                                  2        GND                     
R799             Q_RES_0402LF-33       ,1%  ,1/A 1        SPI_BMC_BIOS_CS0_N      
                                  2        SPI_BMC_BIOS_CS0_R1_N   
R801             Q_RES_0402LF-33       ,1%  ,1/A 1        SPI_BMC_BOOT_CS0_R_N    
                                  2        SPI_BMC_BOOT_CS0_R1_N   
R802             Q_RES_0402LF-33       ,1%  ,1/A 1        SPI_BMC_BOOT_CS1_R_N    
                                  2        SPI_BMC_BOOT_CS1_R1_N   
R803             Q_RES_0402LF-33       ,1%  ,1/A 1        RGMII_BMC_MDC           
                                  2        RGMII_BMC_MDC_R         
R804             Q_RES_0402LF-33       ,1%  ,1/A 1        RGMII_BMC_MDIO          
                                  2        RGMII_BMC_MDIO_R        
R806             Q_RES_0402LF-4.7K,5%,1/16W,CHIA 1        P3V3_AUX                
                                  2        PU_25M_FPGA_CLK_EN      
R807             Q_RES_0402LF-33       ,1%  ,1/A 1        CLK_25M_OSC_FPGA_R      
                                  2        CLK_25M_OSC_FPGA        
R808             Q_RES_0402LF-10K,0.10%,1/16W,CA 1        PU_FPGA_CONFIG_DONE     
                                  2        P3V3_AUX                
R809             Q_RES_0402LF-10K,0.10%,1/16W,CA 1        PU_FPGA_NCONFIG         
                                  2        P3V3_AUX                
R810             Q_RES_0402LF-10K,0.10%,1/16W,CA 1        PU_FPGA_NSTATUS         
                                  2        P3V3_AUX                
R811             Q_RES_0402LF-10K,0.10%,1/16W,CA 1        PD_FPGA_CONFIG_SEL      
                                  2        GND                     
R812             Q_RES_0402LF-33       ,1%  ,1/A 1        PWR_LED_BUF             
                                  2        PWR_LED_BUF_R           
R813             Q_RES_0402LF-33       ,1%  ,1/A 1        ID_LED_BUF              
                                  2        ID_LED_BUF_R            
R814             Q_RES_0402LF-10K,0.10%,1/16W,CA 1        P3V3_AUX                
                                  2        PWR_LED_BUF_R           
R815             Q_RES_0402LF-10K,0.10%,1/16W,CA 1        P3V3_AUX                
                                  2        ID_LED_BUF_R            
R816             Q_RES_0402LF-10,1%,1/16W,CHIP,A 1        P3V3_LED                
                                  2        P3V3_AUX                
R817             Q_RES_0402LF-100K,1%,1/16W,EMPB 1        SMB_BMC_MM13_R_SCL      
                                  2        GND                     
R818             Q_RES_0402LF-100K,1%,1/16W,EMPB 1        SMB_BMC_MM13_R_SDA      
                                  2        GND                     
R819             Q_RES_0402LF-100K,1%,1/16W,EMPB 1        SMB_BMC_MM14_R_SCL      
                                  2        GND                     
R820             Q_RES_0402LF-100K,1%,1/16W,EMPB 1        SMB_BMC_MM14_R_SDA      
                                  2        GND                     
R821             Q_RES_0402LF-4.7K,5%,1/16W,EMPA 1        P3V3_AUX                
                                  2        FM_BMC_ONCTL_R_N        
R822             Q_RES_0402LF-0,5%,1/16W,CHIP,CA 1        FM_PRSNT_1_N            
                                  2        FM_PRSNT_0_R_N          
R823             Q_RES_0402LF-100K,1%,1/16W,CHIA 1        GND                     
                                  2        FM_VIRTUAL_RESEAT       
R824             Q_RES_0402LF-33       ,1%  ,1/A 1        FM_VIRTUAL_RESEAT       
                                  2        FM_VIRTUAL_RESEAT_BMC   
R825             Q_RES_0402LF-33       ,1%  ,1/A 1        RST_ROT_CPU_N           
                                  2        RST_ROT_CPU_R_N         
R828             Q_RES_0402LF-4.7K,5%,1/16W,CHIA 1        P3V3_AUX                
                                  2        RST_ROT_CPU_N           
R829             Q_RES_0402LF-25.5K,1%,1/16W,CHA 1        P2V5_AUX                
                                  2        PU39_ADJ                
R830             Q_RES_0402LF-12K,1%,1/16W,CHIPA 1        PU39_ADJ                
                                  2        GND                     
R831             Q_RES_0402LF-15K,1%,1/16W,CHIPA 1        P1V8_AUX                
                                  2        PU40_ADJ                
R832             Q_RES_0402LF-12K,1%,1/16W,CHIPA 1        PU40_ADJ                
                                  2        GND                     
R833             Q_RES_0402LF-33       ,1%  ,1/A 1        FM_ESPI_PLD_EN          
                                  2        FM_ESPI_PLD_R_EN        
R836             Q_RES_0402LF-33       ,1%  ,1/A 1        PWRGD_PSU_AC_PWROK      
                                  2        PWRGD_PSU_AC_PWROK_BMC  
R837             Q_RES_0402LF-33       ,1%  ,1/B 1        PWRGD_PSU_AC_PWROK      
                                  2        PWRGD_PSU_AC_PWROK_PLD  
R839             Q_RES_0402LF-8.2K     ,5%  ,1/A 1        PWR_LED                 
                                  2        GND                     
R840             Q_RES_0402LF-33       ,1%  ,1/A 1        PWRGD_SYS_PWROK         
                                  2        PWRGD_SYS_PWROK_BMC     
R841             Q_RES_0402LF-33       ,1%  ,1/A 1        PWRGD_SYS_PWROK_PLD     
                                  2        PWRGD_SYS_PWROK         
R842             Q_RES_0402LF-4.7K,5%,1/16W,CHIA 1        P3V3_AUX                
                                  2        SMB_BMC_ALERT9_N        
R843             Q_RES_0402LF-4.7K,5%,1/16W,CHIA 1        P3V3_AUX                
                                  2        SMB_BMC_ALERT10_N       
R844             Q_RES_0402LF-4.7K,5%,1/16W,CHIA 1        P3V3_AUX                
                                  2        SMB_BMC_ALERT12_N       
R845             Q_RES_0402LF-4.7K,5%,1/16W,EMPA 1        P3V3_AUX                
                                  2        FM_MASTER_MB_N          
R846             Q_RES_0402LF-4.7K,5%,1/16W,EMPA 1        P3V3_AUX                
                                  2        FM_BMC_EN_DET_R         
R848             Q_RES_0402LF-4.7K,5%,1/16W,CHIA 1        P3V3_AUX                
                                  2        SMB_BMC_ALERT16_N       
R851             Q_RES_0402LF-4.7K,5%,1/16W,CHIA 1        P3V3_AUX                
                                  2        SMB_BMC_ALERT15_N       
R852             Q_RES_0402LF-33       ,1%  ,1/A 1        FM_BMC_MUX_CS_SPI_SEL_0 
                                  2        FM_BMC_BIOS_MUX_CS_SPI_R_SEL_0
R859             Q_RES_0402LF-33       ,1%  ,1/A 1        SPI_SYS_R_CLK           
                                  2        SPI_SYS_MUX_CLK         
R860             Q_RES_0402LF-33       ,1%  ,1/A 1        SPI_SYS_R_MOSI          
                                  2        SPI_SYS_MUX_MOSI        
R861             Q_RES_0402LF-33       ,1%  ,1/A 1        SPI_SYS_R_MISO          
                                  2        SPI_SYS_MUX_MISO        
R862             Q_RES_0402LF-33       ,1%  ,1/A 1        SPI_SYS_WP_R_IO2        
                                  2        SPI_SYS_MUX_WP_IO2      
R863             Q_RES_0402LF-33       ,1%  ,1/A 1        SPI_SYS_HOLD_R_IO3      
                                  2        SPI_SYS_MUX_HOLD_IO3    
R864             Q_RES_0402LF-33       ,1%  ,1/A 1        SPI_SYS_CS0_N           
                                  2        SPI_PCH_SECURE_CS0_N    
R866             Q_RES_0402LF-10K,1%,1/16W,CHIPA 1        FM_BMC_BIOS_MUX_CS_SPI_R_SEL_0
                                  2        GND                     
R870             Q_RES_0402LF-4.7K,5%,1/16W,EMPA 1        P3V3_AUX                
                                  2        PD_BIOS_MUX_EN_N        
SW1              SW4S_DHNF02FTVTR-SW4S_DHNF-02FA 1        PD_BMC_DISABLE          
                                  2        PU_JTAG_TCK_MUX         
                                  3        FM_BMC_DISABLE          
                                  4        FM_JTAG_TCK_MUX_BMC_SEL_R
SW2              SW4S_DHNF02FTVTR-SW4S_DHNF-02FA 1        PD_SPI_BMC_BOOT_MOSI    
                                  2        PU_SPI_BMC_BOOT_MISO    
                                  3        SPI_BMC_BOOT_MOSI       
                                  4        SPI_BMC_BOOT_MISO       
SW3              SW4S_DHNF02FTVTR-SW4S_DHNF-02FA 1        PD_BMC_DEBUG            
                                  2        PD_JTAGEN               
                                  3        FM_BMC_DEBUG_SW_N       
                                  4        MB_JTAG_PLD_R_JTAGEN    
SW6              SW2S_TA31E2KQTR-SW2S_TA3-1E2K-A 1        GND                     
                                  2        REAR_PWR_BTN_N          
                                  G1       GND                     
                                  G2       GND                     
                                  G3       GND                     
SW7              SW2S_TA31E2KQTR-SW2S_TA3-1E2K-A 1        GND                     
                                  2        REAR_ID_RST_BTN_N       
                                  G1       GND                     
                                  G2       GND                     
                                  G3       GND                     
U1               K4A8G165WCBCTD-K4A8G165WC-BCTDA A1       P1V2_AUX                
                                  A2       GND                     
                                  A3       M_BMC_DDR4_DQ<8>        
                                  A7       M_BMC_DDR4_DQS1_N       
                                  A8       GND                     
                                  A9       P1V2_AUX                
                                  B1       P2V5_AUX                
                                  B2       GND                     
                                  B3       P1V2_AUX                
                                  B7       M_BMC_DDR4_DQS1_P       
                                  B8       M_BMC_DDR4_DQ<9>        
                                  B9       P1V2_AUX                
                                  C1       P1V2_AUX                
                                  C2       M_BMC_DDR4_DQ<12>       
                                  C3       M_BMC_DDR4_DQ<10>       
                                  C7       M_BMC_DDR4_DQ<11>       
                                  C8       M_BMC_DDR4_DQ<13>       
                                  C9       GND                     
                                  D1       P1V2_AUX                
                                  D2       GND                     
                                  D3       M_BMC_DDR4_DQ<14>       
                                  D7       M_BMC_DDR4_DQ<15>       
                                  D8       GND                     
                                  D9       P1V2_AUX                
                                  E1       GND                     
                                  E2       M_BMC_DDR4_MDM1         
                                  E3       GND                     
                                  E7       M_BMC_DDR4_MDM0         
                                  E8       GND                     
                                  E9       M_BMC_DDR4_ZQU          
                                  F1       GND                     
                                  F2       P1V2_AUX                
                                  F3       M_BMC_DDR4_DQS0_N       
                                  F7       M_BMC_DDR4_DQ<1>        
                                  F8       P1V2_AUX                
                                  F9       PD_M_BMC_DDR4_ZQ        
                                  G1       P1V2_AUX                
                                  G2       M_BMC_DDR4_DQ<0>        
                                  G3       M_BMC_DDR4_DQS0_P       
                                  G7       P1V2_AUX                
                                  G8       GND                     
                                  G9       P1V2_AUX                
                                  H1       GND                     
                                  H2       M_BMC_DDR4_DQ<4>        
                                  H3       M_BMC_DDR4_DQ<2>        
                                  H7       M_BMC_DDR4_DQ<3>        
                                  H8       M_BMC_DDR4_DQ<5>        
                                  H9       GND                     
                                  J1       P1V2_AUX                
                                  J2       P1V2_AUX                
                                  J3       M_BMC_DDR4_DQ<6>        
                                  J7       M_BMC_DDR4_DQ<7>        
                                  J8       P1V2_AUX                
                                  J9       P1V2_AUX                
                                  K1       GND                     
                                  K2       M_BMC_DDR4_MCKE         
                                  K3       M_BMC_DDR4_MODT         
                                  K7       M_BMC_DDR4_MCLK_DP      
                                  K8       M_BMC_DDR4_MCLK_DN      
                                  K9       GND                     
                                  L1       P1V2_AUX                
                                  L2       M_BMC_DDR4_MWE_N        
                                  L3       M_BMC_DDR4_MACT_N       
                                  L7       M_BMC_DDR4_MCS_N        
                                  L8       M_BMC_DDR4_MRAS_N       
                                  L9       P1V2_AUX                
                                  M1       P0V6_DDR_VREF_AUX       
                                  M2       M_BMC_DDR4_MBG0         
                                  M3       M_BMC_DDR4_MA<10>       
                                  M7       M_BMC_DDR4_MA<12>       
                                  M8       M_BMC_DDR4_MCAS_N       
                                  M9       M_BMC_DDR4_BG1          
                                  N1       GND                     
                                  N2       M_BMC_DDR4_MBA0         
                                  N3       M_BMC_DDR4_MA<4>        
                                  N7       M_BMC_DDR4_MA<3>        
                                  N8       M_BMC_DDR4_MBA1         
                                  N9       PD_M_BMC_DDR4_TEN       
                                  P1       M_BMC_DDR4_RST_N        
                                  P2       M_BMC_DDR4_MA<6>        
                                  P3       M_BMC_DDR4_MA<0>        
                                  P7       M_BMC_DDR4_MA<1>        
                                  P8       M_BMC_DDR4_MA<5>        
                                  P9       M_BMC_DDR4_ALERT_N      
                                  R1       P1V2_AUX                
                                  R2       M_BMC_DDR4_MA<8>        
                                  R3       M_BMC_DDR4_MA<2>        
                                  R7       M_BMC_DDR4_MA<9>        
                                  R8       M_BMC_DDR4_MA<7>        
                                  R9       P2V5_AUX                
                                  T1       GND                     
                                  T2       M_BMC_DDR4_MA<11>       
                                  T3       PD_M_BMC_DDR4_PAR       
                                  T7       GND                     
                                  T8       M_BMC_DDR4_MA<13>       
                                  T9       P1V2_AUX                
U2               SN74LVC1G3157DCKR-SN74LVC1G315A 1        UART_BMC_1_TXD_R        
                                  2        GND                     
                                  3        UART_BMC_5_TXD_R        
                                  4        SPA_SOUT_SW_BUF         
                                  5        P3V3_AUX                
                                  6        FM_BMC_DEBUG_SW_N       
U3               SN74LVC1G3157DCKR-SN74LVC1G315A 1        UART_BMC_1_RXD_R        
                                  2        GND                     
                                  3        UART_BMC_5_RXD_R        
                                  4        SPA_SIN_SW_BUF          
                                  5        P3V3_AUX                
                                  6        FM_BMC_DEBUG_SW_N       
U4               TMP75AIDGKR-TMP75AIDGKR,SMLF,IA 1        SMB_BMC_MM15_R1_SDA     
                                  2        SMB_BMC_MM15_R1_SCL     
                                  3        SMB_BMC_ALERT15_R_N     
                                  4        GND                     
                                  5        TEMP_A2                 
                                  6        TEMP_A1                 
                                  7        TEMP_A0                 
                                  8        P3V3_AUX                
U5               AST2600A1GP-AST2600A1-GP,SMLF,A A1       GND                     
                                  A2       GND                     
                                  A3       GND                     
                                  A4       USB_HOST_BMC_A_R_DP     
                                  A5       GND                     
                                  A6       USB_HOST_BMC_B_R_DP     
                                  A7       RST_PLTRST_N            
                                  A8       V_BMC_DDC_SDA           
                                  A9       JTAG_SCM_TMS            
                                  A11      SMB_BMC_MM5_R_SCL       
                                  A12      PWRGD_PSU_AC_PWROK_BMC  
                                  A13      SMB_BMC_MM10_R_SDA      
                                  A14      SMB_BMC_MM9_R_SDA       
                                  A15      IRQ_PCH_SCI_WHEA_R_N    
                                  A16      JTAG_1_BMC_TDI_R        
                                  A17      SGPIO_BMC_M1_DI         
                                  A18      SGPIO_BMC_M1_CLK        
                                  A19      SMB_BMC_MM3_R_SDA       
                                  A20      SMB_BMC_MM1_R_SDA       
                                  A21      FM_PLT_BMC_THERMTRIP_N_R
                                  A22      UART_2_BMC_R_RXD        
                                  A23      BMC_CPLD_GPIO_2_R1      
                                  A24      IRQ_SGPIO_BMC_N         
                                  A25      RST_PCA9548_SENSOR_R_N  
                                  A26      GND                     
                                  AA1      GND                     
                                  AA2      DP_BMC_C_TX1_N          
                                  AA3      GND                     
                                  AA4      BMC_EMMC_CMD            
                                  AA5      BMC_EMMC_DT1            
                                  AA6      GND                     
                                  AA7      GND                     
                                  AA8      GND                     
                                  AA10     GND                     
                                  AA11     BMC_CPLD_GPIO_8_R1      
                                  AA12     BMC_CPLD_GPIO_25_R1     
                                  AA13     SPI_BMC_BOOT_CS1_R1_N   
                                  AA14     GND                     
                                  AA15     GND                     
                                  AA16     FM_BMC_EN_DET_R         
                                  AA17     SMB_BMC_ALERT10_R_N     
                                  AA18     PVCCIO_PECI_BMC         
                                  AA19     GND                     
                                  AA20     GND                     
                                  AA21     A_BMC_ADCAV33           
                                  AA22     GND                     
                                  AA23     ID_RST_BTN_BMC_R_N      
                                  AA24     RST_BMC_RSTBTN_OUT_R_N  
                                  AA25     BMC_CPLD_GPIO_15_R1     
                                  AA26     BMC_CPLD_GPIO_22_R1     
                                  AB1      DP_BMC_C_TX0_N          
                                  AB2      DP_BMC_C_TX1_P          
                                  AB3      DP_BMC_AUX_N            
                                  AB4      BMC_EMMC_CLK            
                                  AB5      BMC_EMMC_DT3            
                                  AB6      BMC_EMMC_WP_N           
                                  AB7      ESPI_LPC_D0_IO0         
                                  AB8      ESPI_LPC_D1_IO1         
                                  AB9      SPI_BMC_BIOS_ROM_MOSI   
                                  AB10     SPI_BMC_BIOS_ROM_IO3    
                                  AB11     BMC_CPLD_GPIO_7_R1      
                                  AB12     PU_FWSPIWP_N            
                                  AB13     SPI_BMC_MISO_IO1_R      
                                  AB14     SPI_BMC_BOOT_CS0_R1_N   
                                  AB15     FM_SLPS3_GF_N           
                                  AB16     SMB_BMC_ALERT9_R_N      
                                  AB17     P1V0_SENSOR             
                                  AB18     P1V2_SENSOR             
                                  AB19     PGPPA_BMC_AUX_SENSOR    
                                  AB20     A_BMC_ADCVREFN0         
                                  AB21     PD_INTRUDER_BMC_N       
                                  AB22     FM_PWR_BTN              
                                  AB23     H_CPU0_MEMTRIP_LVC1_N   
                                  AB24     H_CPU1_MEMTRIP_LVC1_N   
                                  AB25     BMC_CPLD_GPIO_16_R1     
                                  AB26     BMC_CPLD_GPIO_18_R1     
                                  AC1      DP_BMC_C_TX0_P          
                                  AC2      GND                     
                                  AC3      DP_BMC_AUX_P            
                                  AC4      BMC_EMMC_DT0            
                                  AC5      BMC_EMMC_CD_N           
                                  AC6      GND                     
                                  AC7      ESPI_LPC_D3_IO3         
                                  AC8      ESPI_LPC_D2_IO2         
                                  AC9      IRQ_SMI_ACTIVE_BMC_N    
                                  AC10     BMC_CPLD_GPIO_5_R1      
                                  AC11     SPI_BMC_CPLD_R_MOSI     
                                  AC12     PU_BMC_FWSPIABR_N       
                                  AC13     SPI_BMC_TPM_CS2_R1_N    
                                  AC14     SPI_BMC_MOSI_IO0_R      
                                  AC15     FM_BMC_ONCTL_R_N        
                                  AC16     FM_MASTER_MB_N          
                                  AC17     SMB_BMC_ALERT16_N       
                                  AC18     P5V_SENSOR              
                                  AC19     P1V8_SENSOR             
                                  AC20     A_BMC_ADCVREFP0         
                                  AC21     A_BMC_DACREST           
                                  AC22     BMC_CPLD_GPIO_24_R1     
                                  AC23     FM_SPD_REMOTE_EN_R      
                                  AC24     FM_ADR_COMPLETE         
                                  AC25     GND                     
                                  AC26     BMC_CPLD_GPIO_20_R1     
                                  AD1      GND                     
                                  AD4      GND                     
                                  AD5      CLK_BMC_GF_DP           
                                  AD6      CLK_BMC_GF_DN           
                                  AD7      IRQ_ESPI_LPC_SERIRQ_ALERT0_N
                                  AD8      RST_ESPI_LPC_BMC_N      
                                  AD9      SPI_BMC_BIOS_ROM_MISO   
                                  AD10     PU_SPI1ABR              
                                  AD11     BMC_CPLD_GPIO_9_R1      
                                  AD12     RST_WDTRST_PLD_R1_N     
                                  AD13     BMC_CPLD_GPIO_4_R1      
                                  AD14     BMC_CPLD_GPIO_6_R1      
                                  AD15     FM_BMC_SUSACK_N         
                                  AD16     FM_PCHHOT_R_N           
                                  AD17     A_BMC_ADCVREFP1         
                                  AD18     A_BMC_ADCVREFN1         
                                  AD19     P2V5_SENSOR             
                                  AD20     P12V_SENSOR             
                                  AD21     V_DACB_R                
                                  AD22     BMC_CPLD_GPIO_23_R1     
                                  AD23     FM_PCIE_M2_SSD0_PRSNT_N 
                                  AD25     FM_ADR_TRIGGER_N        
                                  AD26     FM_PMBUS_ALERT_EN       
                                  AE3      GND                     
                                  AE4      P2E_BMC_RX_DP           
                                  AE5      P2E_BMC_RX_DN           
                                  AE6      GND                     
                                  AE7      ESPI_HOST_LPC_BMC_CLK   
                                  AE8      SPI_BMC_BIOS_CS0_R1_N   
                                  AE9      GND                     
                                  AE10     PU_SPI1WP_N             
                                  AE11     FM_BIOS_DEBUG_EN_R_N    
                                  AE12     SPI_BMC_IO2_R           
                                  AE13     GND                     
                                  AE14     FM_BMC_READY_R_PLD_N    
                                  AE15     BATTERY_DETECT          
                                  AE16     SMB_BMC_ALERT12_N       
                                  AE17     GND                     
                                  AE18     P3V_BAT_SENSOR          
                                  AE19     P3V3_SENSOR             
                                  AE20     GND                     
                                  AE21     V_DACG_R                
                                  AE22     I3C2_SDA_R              
                                  AE23     GND                     
                                  AE24     I3C1_SDA_R              
                                  AE25     I3C4_SCL_R              
                                  AE26     I3C3_SDA_R              
                                  AF1      GND                     
                                  AF4      GND                     
                                  AF5      PCIE_BMC_TX_DP          
                                  AF6      PCIE_BMC_TX_DN          
                                  AF7      ESPI_HOST_LPC_BMC_LFRAME_N
                                  AF8      SPI_BMC_BIOS_ROM_CLK    
                                  AF9      SPI_BMC_BIOS_ROM_IO2    
                                  AF10     BMC_CPLD_GPIO_10_R1     
                                  AF11     RST_BMC_SELF_HW_R1      
                                  AF12     SPI_BMC_IO3_R           
                                  AF13     SPI_BMC_CLK_R           
                                  AF14     RST_RSMRST_R_N          
                                  AF15     IRQ_TPM_SPI_N           
                                  AF16     PECI_BMC_R              
                                  AF17     ADCVREFEXT1             
                                  AF18     A_BMC_ADCREXT1          
                                  AF19     ADCVREFEXT0             
                                  AF20     A_BMC_ADCREXT0          
                                  AF21     V_DACR_R                
                                  AF22     I3C2_SCL_R              
                                  AF23     I3C1_SCL_R              
                                  AF24     I3C4_SDA_R              
                                  AF25     I3C3_SCL_R              
                                  AF26     GND                     
                                  B1       GND                     
                                  B2       GND                     
                                  B3       GND                     
                                  B4       USB_HOST_BMC_A_R_DN     
                                  B5       GND                     
                                  B6       USB_HOST_BMC_B_R_DN     
                                  B7       RST_SPI_FLASH_N         
                                  B8       V_BMC_DDC_SCL           
                                  B9       JTAG_SCM_TCK            
                                  B10      RST_EXTRST_N            
                                  B11      GND                     
                                  B12      PWRGD_SYS_PWROK_BMC     
                                  B13      FM_VIRTUAL_RESEAT_BMC   
                                  B14      V_VGAHS_R               
                                  B15      GND                     
                                  B16      FM_THROTTLE_N           
                                  B17      SMB_BMC_MM15_R_SDA      
                                  B18      SGPIO_BMC_M1_LD         
                                  B19      GND                     
                                  B20      SMB_BMC_MM1_R_SCL       
                                  B21      FM_BMC_DBP_PRESENT_R_N  
                                  B22      UART_1_SCM_R_RXD        
                                  B23      GND                     
                                  B24      RMII_RXER               
                                  B25      RMII_CSRDV              
                                  B26      RMII_RXD1               
                                  C1       GND                     
                                  C2       GND                     
                                  C3       GND                     
                                  C4       GND                     
                                  C5       GND                     
                                  C6       GND                     
                                  C7       DP_BMC_HPD_3V3          
                                  C8       UART_BMC_5_TXD          
                                  C9       JTAG_SCM_TDO            
                                  C10      PD_SP_ENTEST            
                                  C11      SMB_BMC_MM5_R_SDA       
                                  C12      FM_DBP_BMC_PRDY_R_N     
                                  C13      UART_BMC_1_TXD          
                                  C14      V_VGAVS_R               
                                  C15      FM_DBP_CPU_PREQ_GF_N    
                                  C16      JTAG_1_BMC_TDO_R        
                                  C17      SMB_BMC_MM16_R_SCL      
                                  C18      SGPIO_BMC_M1_DO         
                                  C19      SMB_BMC_MM3_R_SCL       
                                  C20      SMB_BMC_MM4_R_SCL       
                                  C21      UART_2_BMC_R_TXD        
                                  C22      BMC_CPLD_GPIO_1_R1      
                                  C23      RST_SGPIO_RESET_BMC_N   
                                  C24      RMII_RXD0               
                                  C25      RMII_OCP_RCLKI          
                                  C26      GND                     
                                  D1       GND                     
                                  D2       GND                     
                                  D3       GND                     
                                  D4       GND                     
                                  D5       GND                     
                                  D6       GND                     
                                  D7       FM_BMC_SSPRST_N         
                                  D8       UART_BMC_5_RXD          
                                  D9       JTAG_SCM_TDI            
                                  D10      BMC_CLK_25M             
                                  D11      SMB_BMC_MM7_R_SCL       
                                  D12      SMB_BMC_MM6_R_SCL       
                                  D13      UART_BMC_1_RXD          
                                  D14      H_CPU0_PROCHOT_LVC1_N   
                                  D15      SMB_BMC_MM9_R_SCL       
                                  D16      JTAG_1_BMC_TMS_R        
                                  D17      JTAG_1_BMC_TRST_R       
                                  D18      SMB_BMC_MM15_R_SCL      
                                  D19      SMB_BMC_MM4_R_SDA       
                                  D20      SMB_BMC_MM2_R_SDA       
                                  D21      SMB_BMC_ALERT15_N       
                                  D22      RST_PLTRST_R_N          
                                  D23      FM_BMC_CPU_FBRK_OUT_N   
                                  D24      BMC_CPLD_GPIO_13_R1     
                                  D25      GND                     
                                  D26      BMC_CPLD_GPIO_12_R1     
                                  E1       GND                     
                                  E2       GND                     
                                  E3       GND                     
                                  E4       GND                     
                                  E5       GND                     
                                  E6       GND                     
                                  E7       P1V0_STBY_PLAVDD        
                                  E8       GND                     
                                  E9       P1V0_STBY_PLAVDD        
                                  E10      RST_BMC_SRST_N          
                                  E11      SMB_BMC_MM7_R_SDA       
                                  E12      SMB_BMC_MM8_R_SDA       
                                  E13      SMB_BMC_MM6_R_SDA       
                                  E14      FM_PECI_SEL_R_N         
                                  E15      SMB_BMC_MM10_R_SCL      
                                  E16      PD_BIOS_MUX_EN_R_N      
                                  E17      JTAG_1_BMC_TCK_R        
                                  E18      SMB_BMC_MM16_R_SDA      
                                  E19      SMB_BMC_MM2_R_SCL       
                                  E20      BMC_CPLD_GPIO_3_R1      
                                  E21      UART_1_SCM_R_TXD        
                                  E22      FM_CPU_RMCA_CATERR_LVT3_R_N
                                  E23      RMII_TXEN_R             
                                  E24      RMII_TXD0_R             
                                  E25      RMII_TXD1_R             
                                  E26      RGMII_BMC_RXD_<3>       
                                  F1       M_BMC_DDR4_MA<2>        
                                  F2       M_BMC_DDR4_MA<10>       
                                  F3       M_BMC_DDR4_MA<0>        
                                  F4       GND                     
                                  F5       GND                     
                                  F6       GND                     
                                  F7       P1V0_STBY_PLAVDD        
                                  F8       GND                     
                                  F9       P1V0_STBY_PLAVDD        
                                  F10      GND                     
                                  F11      JTAG_SCM_NTRST          
                                  F12      GND                     
                                  F13      SMB_BMC_MM8_R_SCL       
                                  F14      GND                     
                                  F15      FM_JTAG_TCK_MUX_BMC_SEL_R1
                                  F16      GND                     
                                  F17      GND                     
                                  F18      GND                     
                                  F19      P3V3_P1V8_I2C_I3C       
                                  F20      P3V3_P1V8_I2C_I3C       
                                  F21      GND                     
                                  F22      RGMII_BMC_TXD_R_<3>     
                                  F23      RGMII_BMC_RXD_<0>       
                                  F24      BMC_CPLD_GPIO_11_R1     
                                  F25      RGMII_BMC_RXD_<2>       
                                  F26      RGMII_BMC_RXD_<1>       
                                  G1       M_BMC_DDR4_MA<11>       
                                  G2       GND                     
                                  G3       M_BMC_DDR4_MBG0         
                                  G4       M_BMC_DDR4_MBA0         
                                  G5       M_BMC_DDR4_MWE_N        
                                  G6       P1V2_AUX                
                                  G21      P3V3_P1V8_SD1VDD        
                                  G22      RGMII_BMC_TXD_R_<2>     
                                  G23      RGMII_BMC_RX_CLK_R      
                                  G24      RGMII_BMC_RX_CTRL       
                                  G25      GND                     
                                  G26      FM_ID_LED_N             
                                  H1       M_BMC_DDR4_MACT_N       
                                  H2       M_BMC_DDR4_MCS_N        
                                  H3       M_BMC_DDR4_MA<3>        
                                  H4       GND                     
                                  H5       M_BMC_DDR4_MBA1         
                                  H6       P1V2_AUX                
                                  H8       P1V8_AUX                
                                  H9       GND                     
                                  H10      GND                     
                                  H11      GND                     
                                  H12      P1V8_AUX                
                                  H13      GND                     
                                  H14      P3V3_STBY_PLLAHVDD      
                                  H15      P3V3_AUX                
                                  H16      P3V3_AUX                
                                  H17      P3V3_AUX                
                                  H18      P3V3_P1V8_SD2VDD        
                                  H19      P3V3_P1V8_SD2VDD        
                                  H21      P3V3_P1V8_SD1VDD        
                                  H22      RGMII_BMC_TXD_R_<0>     
                                  H23      RGMII_BMC_TXD_R_<1>     
                                  H24      RGMII_BMC_TX_R_CLK      
                                  H25      FM_ESPI_PLD_R1_EN       
                                  H26      SMB_BMC_ALERT3_R_N      
                                  J1       M_BMC_DDR4_MODT         
                                  J2       GND                     
                                  J3       M_BMC_DDR4_MA<4>        
                                  J4       M_BMC_DDR4_MCAS_N       
                                  J5       M_BMC_DDR4_MRAS_N       
                                  J6       P1V2_AUX                
                                  J8       P1V8_AUX                
                                  J9       P1V0_STBY_PLAVDD        
                                  J10      P3V3_BMC_USB2AV33       
                                  J11      GND                     
                                  J12      P1V8_AUX                
                                  J13      GND                     
                                  J14      GND                     
                                  J15      GND                     
                                  J16      GND                     
                                  J17      GND                     
                                  J18      GND                     
                                  J19      GND                     
                                  J21      P3V3_P2V5_P1V8_RVDD     
                                  J22      RGMII_BMC_TX_R_CTRL     
                                  J23      FM_BMC_MUX_CS_SPI_SEL_0 
                                  J24      IRQ_BMC_CPU_NMI         
                                  J25      SMB_BMC_ALERT4_R_N      
                                  J26      FM_ME_BT_DONE           
                                  K1       M_BMC_DDR4_MCLK_DN      
                                  K2       M_BMC_DDR4_MCLK_DP      
                                  K3       M_BMC_DDR4_MA<13>       
                                  K4       GND                     
                                  K5       M_BMC_DDR4_MA<1>        
                                  K6       P1V2_AUX                
                                  K8       GND                     
                                  K9       GND                     
                                  K10      P1V8_BMC_USB2AV18       
                                  K11      P3V3_RGM                
                                  K12      P3V3_RGM                
                                  K13      GND                     
                                  K14      GND                     
                                  K15      GND                     
                                  K16      P1V2_AUX                
                                  K17      P1V2_AUX                
                                  K18      P1V2_AUX                
                                  K19      P1V2_AUX                
                                  K21      P3V3_P2V5_P1V8_RVDD     
                                  K22      GND                     
                                  K23      VOL_SEN_ALERT_R         
                                  K24      SMB_BMC_MM12_R_SDA      
                                  K25      SMB_BMC_MM14_R_SDA      
                                  K26      SMB_BMC_MM13_R_SCL      
                                  L1       M_BMC_DDR4_MA<5>        
                                  L2       GND                     
                                  L3       M_BMC_DDR4_RST_N        
                                  L4       M_BMC_DDR4_MA<12>       
                                  L5       M_BMC_DDR4_MCKE         
                                  L6       P1V2_AUX                
                                  L8       GND                     
                                  L9       P1V0_AUX                
                                  L10      P1V0_AUX                
                                  L11      GND                     
                                  L12      GND                     
                                  L13      P1V8_AUX                
                                  L14      P1V2_AUX                
                                  L15      GND                     
                                  L16      GND                     
                                  L17      GND                     
                                  L18      GND                     
                                  L19      GND                     
                                  L21      P1V2_AUX                
                                  L22      P3V3_P2V5_P1V8_RVDD     
                                  L23      SMB_BMC_MM14_R_SCL      
                                  L24      SMB_BMC_MM13_R_SDA      
                                  L25      GND                     
                                  L26      SMB_BMC_MM12_R_SCL      
                                  M1       M_BMC_DDR4_MA<8>        
                                  M2       M_BMC_DDR4_MA<7>        
                                  M3       M_BMC_DDR4_MBG1         
                                  M4       GND                     
                                  M5       M_BMC_DDR4_MA<6>        
                                  M6       P1V2_STBY_MVDD_CK       
                                  M8       P1V0_AUX                
                                  M9       GND                     
                                  M10      GND                     
                                  M11      P1V0_AUX                
                                  M12      GND                     
                                  M13      P1V8_AUX                
                                  M14      P1V2_AUX                
                                  M15      GND                     
                                  M16      GND                     
                                  M17      GND                     
                                  M18      GND                     
                                  M19      GND                     
                                  M21      P1V2_AUX                
                                  M22      P3V3_P2V5_P1V8_RVDD     
                                  M23      LED_POSTCODE_5_N        
                                  M24      RGMII_BMC_MDC           
                                  M25      RGMII_BMC_MDIO          
                                  M26      LED_POSTCODE_7_N        
                                  N1       M_BMC_DDR4_MA<9>        
                                  N2       GND                     
                                  N3       M_BMC_DDR4_MDM0         
                                  N4       M_BMC_DDR4_ALERT_N      
                                  N5       P1V8_STBY_AVDDPLL       
                                  N6       GND                     
                                  N8       P1V0_AUX                
                                  N9       GND                     
                                  N10      GND                     
                                  N11      P1V0_AUX                
                                  N12      P1V8_AUX                
                                  N13      P1V8_AUX                
                                  N14      P1V2_AUX                
                                  N15      GND                     
                                  N16      GND                     
                                  N17      GND                     
                                  N18      GND                     
                                  N19      GND                     
                                  N21      P1V2_AUX                
                                  N22      P3V3_AUX                
                                  N23      LED_POSTCODE_1_N        
                                  N24      LED_POSTCODE_3_N        
                                  N25      LED_POSTCODE_2_N        
                                  N26      LED_POSTCODE_6_N        
                                  P1       M_BMC_DDR4_DQ<5>        
                                  P2       M_BMC_DDR4_DQ<6>        
                                  P3       M_BMC_DDR4_DQ<7>        
                                  P4       GND                     
                                  P5       IBMC_MIOZ               
                                  P6       P1V2_AUX                
                                  P8       P1V0_AUX                
                                  P9       GND                     
                                  P10      GND                     
                                  P11      P1V0_AUX                
                                  P12      P1V8_AUX                
                                  P13      P1V8_AUX                
                                  P14      P1V2_AUX                
                                  P15      GND                     
                                  P16      GND                     
                                  P17      GND                     
                                  P18      GND                     
                                  P19      GND                     
                                  P21      P1V2_AUX                
                                  P22      P3V3_AUX                
                                  P23      FM_RISER1_JTAG_SEL_R_N  
                                  P24      H_CPU1_PROCHOT_LVC1_N   
                                  P25      LED_POSTCODE_0_N        
                                  P26      LED_POSTCODE_4_N        
                                  R1       M_BMC_DDR4_DQ<4>        
                                  R2       GND                     
                                  R3       M_BMC_DDR4_DQ<3>        
                                  R4       M_BMC_DDR4_DQ<1>        
                                  R5       M_BMC_DDR4_MDM1         
                                  R6       P1V2_AUX                
                                  R8       GND                     
                                  R9       P1V0_AUX                
                                  R10      P1V0_AUX                
                                  R11      GND                     
                                  R12      P1V8_AUX                
                                  R13      P1V8_AUX                
                                  R14      P1V2_AUX                
                                  R15      GND                     
                                  R16      GND                     
                                  R17      GND                     
                                  R18      GND                     
                                  R19      GND                     
                                  R21      P1V2_AUX                
                                  R22      P3V3_AUX                
                                  R23      IRQ_BMC_PCH_NMI_N       
                                  R24      FM_INTRUDER_HDR_PCH_R_N 
                                  R25      GND                     
                                  R26      FM_BMC_DEBUG_SW_N       
                                  T1       M_BMC_DDR4_DQS0_N       
                                  T2       M_BMC_DDR4_DQS0_P       
                                  T3       M_BMC_DDR4_DQ<0>        
                                  T4       GND                     
                                  T5       P0V6_DDR_VREF_AUX       
                                  T6       P1V2_AUX                
                                  T8       P1V0_STBY_DP_VCC10A     
                                  T9       P1V0_STBY_PE_VCC10A     
                                  T10      P1V0_STBY_RC_VCC10A     
                                  T11      GND                     
                                  T12      GND                     
                                  T13      P1V8_AUX                
                                  T14      P1V2_AUX                
                                  T15      GND                     
                                  T16      GND                     
                                  T17      GND                     
                                  T18      GND                     
                                  T19      GND                     
                                  T21      P1V2_AUX                
                                  T22      P3V3_AUX                
                                  T23      PWRGD_PCH_PWROK         
                                  T24      FM_RISER2_JTAG_SEL_R_N  
                                  T25      BMC_CPLD_GPIO_14_R1     
                                  T26      FM_THERMTRIP_DLY_LVC1_R_N
                                  U1       M_BMC_DDR4_DQ<2>        
                                  U2       GND                     
                                  U3       M_BMC_DDR4_DQ<15>       
                                  U4       M_BMC_DDR4_DQ<13>       
                                  U5       P0V6_DDR_VREF_AUX       
                                  U6       P1V8_AUX                
                                  U8       GND                     
                                  U9       GND                     
                                  U10      GND                     
                                  U11      GND                     
                                  U12      GND                     
                                  U13      P1V8_AUX                
                                  U14      GND                     
                                  U15      P1V2_AUX                
                                  U16      P1V2_AUX                
                                  U17      P1V2_AUX                
                                  U18      P1V2_AUX                
                                  U19      GND                     
                                  U21      P1V2_P1V0_I3C_VDDL2     
                                  U22      GND                     
                                  U23      GND                     
                                  U24      IRQ_UV_DETECT_N         
                                  U25      IRQ_CPU1_VRHOT_N        
                                  U26      FM_BIOS_POST_CMPLT_BMC_N
                                  V1       M_BMC_DDR4_DQS1_N       
                                  V2       M_BMC_DDR4_DQS1_P       
                                  V3       M_BMC_DDR4_DQ<9>        
                                  V4       M_BMC_DDR4_DQ<14>       
                                  V5       GND                     
                                  V6       P1V8_AUX                
                                  V8       P1V8_STBY_DP_VCC18A     
                                  V9       P1V8_STBY_PE_VCC18A     
                                  V10      P1V8_STBY_RC_VCC18A     
                                  V11      GND                     
                                  V12      GND                     
                                  V13      P1V8_AUX                
                                  V14      GND                     
                                  V15      GND                     
                                  V16      GND                     
                                  V17      GND                     
                                  V18      GND                     
                                  V19      GND                     
                                  V21      P3V3_STBY_DACAV33       
                                  V22      P1V2_P1V0_I3C_VDDL1     
                                  V23      P3V3_RTC_AUX            
                                  V24      IRQ_OC_DETECT_EN_N      
                                  V25      IRQ_OC_DETECT_N         
                                  V26      IRQ_CPU0_VRHOT_N        
                                  W1       M_BMC_DDR4_DQ<10>       
                                  W2       M_BMC_DDR4_DQ<8>        
                                  W3       M_BMC_DDR4_DQ<11>       
                                  W4       M_BMC_DDR4_DQ<12>       
                                  W5       GND                     
                                  W6       GND                     
                                  W8       GND                     
                                  W9       GND                     
                                  W10      GND                     
                                  W11      GND                     
                                  W12      GND                     
                                  W13      P1V8_AUX                
                                  W14      P1V8_AUX                
                                  W15      PGPPA_BMC_AUX           
                                  W16      P3V3_AUX                
                                  W17      P3V3_AUX                
                                  W18      P3V3_AUX                
                                  W19      P3V3_AUX                
                                  W21      P3V3_STBY_DACAV33       
                                  W22      GND                     
                                  W23      BMC_PWR_LED             
                                  W24      SYS_BMC_PWRBTN_R_N      
                                  W25      GND                     
                                  W26      PWRGD_CPUPWRGD_LVC1     
                                  Y1       BMC_EMMC_DT4            
                                  Y2       BMC_EMMC_DT5            
                                  Y3       BMC_EMMC_DT6            
                                  Y4       BMC_EMMC_DT7            
                                  Y5       BMC_EMMC_DT2            
                                  Y6       GND                     
                                  Y21      A_BMC_ADCAV33           
                                  Y22      GND                     
                                  Y23      BMC_HEARTBEAT_N         
                                  Y24      BMC_CPLD_GPIO_17_R1     
                                  Y25      BMC_CPLD_GPIO_21_R1     
                                  Y26      BMC_CPLD_GPIO_19_R1     
U6               SN74LVC2G07DCKR_SMLF-SN74LVC2GA 1        PWRGD_P1V0_AUX_DELAY    
                                  2        GND                     
                                  3        RST_SRST_PLD_BMC_R_N    
                                  4        RST_SRST_PLD_BMC_BUF_N  
                                  5        P3V3_AUX                
                                  6        PWRGD_P1V0_AUX_DELAY_BUF
U7               BCM54612EB1KMLG-BCM54612EB1KMLA 1        P3V3_AUX                
                                  2        P1V2_PHY0               
                                  3        P1V2_PHY0               
                                  4        P3V3_AUX                
                                  5        GND                     
                                  6        GND                     
                                  7        XTAL_PHY_XO             
                                  8        XTAL_PHY_XI             
                                  9        P3V3_XTALVDD            
                                  10       PHY_RDAC                
                                  11       P1V2_PHY0_PLLVDD        
                                  12       P3V3_BIASVDD            
                                  13       P1V2_PHY0_AVDDL         
                                  14       PHY_TRD_0_P             
                                  15       PHY_TRD_0_N             
                                  16       P3V3_AVDD               
                                  17       PHY_TRD_1_N             
                                  18       PHY_TRD_1_P             
                                  19       P1V2_PHY0_AVDDL         
                                  20       PHY_TRD_2_P             
                                  21       PHY_TRD_2_N             
                                  22       P3V3_AVDD               
                                  23       PHY_TRD_3_N             
                                  24       PHY_TRD_3_P             
                                  25       P1V2_PHY0_AVDDL         
                                  26       RGMII_BMC_RX_R_CTRL     
                                  27       RGMII_BMC_R_RXD_<3>     
                                  28       RGMII_BMC_R_RXD_<2>     
                                  29       P3V3_AUX                
                                  30       P1V2_PHY0               
                                  31       RGMII_BMC_R_RXD_<1>     
                                  32       RGMII_BMC_R_RXD_<0>     
                                  33       RGMII_BMC_RX_CLK        
                                  34       P3V3_AUX                
                                  35       RGMII_BMC_TX_CTRL       
                                  36       RGMII_BMC_TXD_<3>       
                                  37       RGMII_BMC_TXD_<2>       
                                  38       RGMII_BMC_TXD_<1>       
                                  39       RGMII_BMC_TXD_<0>       
                                  40       RGMII_BMC_TX_CLK        
                                  41       PHYA0                   
                                  43       PHY_LED3                
                                  44       PHY_LED2                
                                  45       PHY_LED1                
                                  46       RST_RSTB_N              
                                  47       RGMII_BMC_MDIO_R        
                                  48       RGMII_BMC_MDC_R         
                                  TH       GND                     
U8               TPD4E001DBVR-TPD4E001DBVR,SMLFB 1        PHY_TRD_0_N             
                                  2        GND                     
                                  3        PHY_TRD_1_N             
                                  4        PHY_TRD_1_P             
                                  5        PU_RJ45_ESD             
                                  6        PHY_TRD_0_P             
U9               TPD4E001DBVR-TPD4E001DBVR,SMLFB 1        PHY_TRD_2_N             
                                  2        GND                     
                                  3        PHY_TRD_3_N             
                                  4        PHY_TRD_3_P             
                                  5        PU_RJ45_ESD             
                                  6        PHY_TRD_2_P             
U10              TPS2553DBVR1-TPS2553DBVR-1,SMLA 1        P5V_AUX                 
                                  2        GND                     
                                  3        USB_OC0_EN              
                                  4        USB_OC0_REAR_N          
                                  5        USB_OC0_ILIM            
                                  6        P5V_USB_REAR            
U11              BAT54C-BAT54C,SMLF,IC,BCBAT54CA 1        FM_BMC_ONCTL_R_N        
                                  2        UART_BMC_5_TXD_R        
                                  3        FM_BMC_DISABLE          
U12              MOSFET_N_SMLF-BSS138K,BSS138K,A D        RST_BMC_EXTRST_R1_N     
                                  G        RST_BMC_SELF_HW_D_C     
                                  S        GND                     
U13              SN74LVC1G07DCKR-SN74LVC1G07DCKA 2        RST_BMC_SRST_BUF_R1_N   
                                  3        GND                     
                                  4        RST_BMC_EXTRST_R1_N     
                                  5        P3V3_AUX                
U14              AP22811AW57-AP22811AW5-7,SMLF,A 1        P3V3_RGM                
                                  2        GND                     
                                  4        PWRGD_P1V8_AUX_R2       
                                  5        P3V3_AUX                
U15              TPS22965DSGR-TPS22965DSGR,SMLFA 1        P3V3_AUX                
                                  2        P3V3_AUX                
                                  3        PU_LOADSW_EN            
                                  4        LOADSW_VBIAS            
                                  5        GND                     
                                  6        LOADSW_CT               
                                  7        P3V3_DP                 
                                  8        P3V3_DP                 
                                  TH       GND                     
U16              TPD4E001DBVR-TPD4E001DBVR,SMLFA 1        DP_BMC_TX1_P            
                                  2        GND                     
                                  3        DP_BMC_TX1_N            
                                  4        DP_BMC_TX0_N            
                                  5        P3V3_DP_L               
                                  6        DP_BMC_TX0_P            
U17              FT234XDR-FT234XD-R,SMLF,IC,AL0A 1        USB2_PL2303_EXT_DN      
                                  2        P3V3_PL2303             
                                  3        P3V3_PL2303             
                                  4        P5V_BUS                 
                                  5        GND                     
                                  7        SPA_SIN_SW_MNUSB_R      
                                  9        P3V3_PL2303             
                                  10       SPA_SOUT_SW_MNUSB       
                                  12       USB2_PL2303_EXT_DP      
                                  13       GND                     
U18              TPD2EUSB30DRTR_SMLF-TPD2EUSB30A 1        USB2_EXT_R_DP           
                                  2        USB2_EXT_R_DN           
                                  3        GND                     
U19              M24128BWDW6TP-M24128-BWDW6TP,SA 1        FRU_E0                  
                                  2        FRU_E1                  
                                  3        FRU_E2                  
                                  4        GND                     
                                  5        SMB_BMC_MM15_R2_SDA     
                                  6        SMB_BMC_MM15_R2_SCL     
                                  7        PD_FRU_WC_N             
                                  8        P3V3_AUX                
U20              MTFC8GAKAJCN1MWT-MTFC8GAKAJCN-A A3       EMMC_DT0_R              
                                  A4       EMMC_DT1_R              
                                  A5       EMMC_DT2_R              
                                  A6       GND                     
                                  B2       EMMC_DT3_R              
                                  B3       EMMC_DT4_R              
                                  B4       EMMC_DT5_R              
                                  B5       EMMC_DT6_R              
                                  B6       EMMC_DT7_R              
                                  C2       VDDI_U2_EMMC            
                                  C4       GND                     
                                  C6       P1V8_AUX                
                                  E6       P3V3_AUX                
                                  E7       GND                     
                                  F5       P3V3_AUX                
                                  G5       GND                     
                                  H10      GND                     
                                  J5       GND                     
                                  J10      P3V3_AUX                
                                  K5       BMC_EMMC_RST_N          
                                  K8       GND                     
                                  K9       P3V3_AUX                
                                  M4       P1V8_AUX                
                                  M5       EMMC_CMD_R              
                                  M6       EMMC_CLK_R              
                                  N2       GND                     
                                  N4       P1V8_AUX                
                                  N5       GND                     
                                  P3       P1V8_AUX                
                                  P4       GND                     
                                  P5       P1V8_AUX                
                                  P6       GND                     
U21              IDTQS3VH257PAG_SMLF-IDTQS3VH25A 1        FM_BMC_BIOS_MUX_CS_SPI_R_SEL_0
                                  2        SPI_SYS_MUX_WP_IO2      
                                  3        SPI_BMC_BIOS_ROM_R_IO2  
                                  4        SPI_PCH_MUXED_IO2       
                                  5        SPI_SYS_MUX_MISO        
                                  6        SPI_BMC_BIOS_ROM_R_MISO 
                                  7        SPI_PCH_MUXED_IO1       
                                  8        GND                     
                                  9        SPI_PCH_MUXED_CS0_N     
                                  10       SPI_BMC_BIOS_SOURCE_CS0_N
                                  11       SPI_PCH_SECURE_CS0_N    
                                  15       PD_BIOS_MUX_EN_N        
                                  16       P3V3_AUX                
U23              SN74LVC1G07DBVR_SMLF-SN74LVC1GA 2        DEBUG_PORT_PRSNT        
                                  3        GND                     
                                  4        DEBUG_PORT_PRSNT_BUF_EN 
                                  5        P3V3_AUX                
U24              SN74LVC2G07DCKR_SMLF-SN74LVC2GA 1        UART_BMC_5_TXD_R        
                                  2        GND                     
                                  3        UART_BMC_5_RXD_BUF      
                                  4        UART_BMC_5_RXD_BUF_R    
                                  5        P3V3_AUX                
                                  6        UART_BMC_5_TXD_BUF      
U25              10M02SCU169C8G-10M02SCU169C8G,A A1       GND                     
                                  A2       PWRGD_P1V2_AUX_R1       
                                  A3       PWRGD_P5V_AUX_R1        
                                  A4       FM_RISER2_JTAG_SEL_N    
                                  A5       PWRGD_P3V3_RGM_R1       
                                  A6       FM_BIOS_DEBUG_EN_N      
                                  A7       FM_BMC_READY_PLD_N      
                                  A10      FM_PWR_R_BTN            
                                  A11      PWRGD_SYS_PWROK_PLD     
                                  A13      GND                     
                                  B1       RST_PLTRST_R1_N         
                                  B2       PWRGD_P1V0_AUX_R1       
                                  B3       PWRGD_P2V5_AUX_R1       
                                  B4       PWRGD_P1V8_AUX_R1       
                                  B5       PWR_LED_CPLD            
                                  B6       FM_RISER1_JTAG_SEL_N    
                                  B7       SMB_BMC_ALERT12_N       
                                  B8       GND                     
                                  C1       FM_TPM_PRSNT_1_R_N      
                                  C2       IRQ_BMC_CPU_NMI_R       
                                  C3       GND                     
                                  C4       PU_FPGA_NSTATUS         
                                  C5       PU_FPGA_CONFIG_DONE     
                                  C6       P3V3_AUX                
                                  C7       P3V3_AUX                
                                  C8       P3V3_AUX                
                                  C13      BMC_CPLD_GPIO_25_R2     
                                  D1       FM_TPM_PRSNT_0_R_N      
                                  D4       PVCCD_PLL_AUX           
                                  D5       GND                     
                                  D7       PD_FPGA_CONFIG_SEL      
                                  D9       SMB_BMC_MM15_R3_SDA     
                                  D10      PVCCD_PLL_AUX           
                                  D12      RST_BMC_HW_R            
                                  D13      BMC_CPLD_GPIO_23_R2     
                                  E1       BMC_CPLD_GPIO_1_R2      
                                  E3       PWRGD_PSU_AC_PWROK_PLD  
                                  E4       FM_JTAG_TCK_MUX_BMC_SEL 
                                  E5       JTAG_SCM_PLD_JTAGEN     
                                  E6       PWRGD_P3V3_AUX_R1       
                                  E7       PU_FPGA_NCONFIG         
                                  E8       USB_OC0_REAR_R_N        
                                  E10      SMB_BMC_MM15_R3_SCL     
                                  E11      GND                     
                                  E12      BMC_CPLD_GPIO_21_R2     
                                  E13      BMC_CPLD_GPIO_19_R2     
                                  F1       RST_RSMRST_N            
                                  F2       P3V3_AUX                
                                  F3       GND                     
                                  F4       FM_BMC_DBP_PRESENT_N    
                                  F5       JTAG_SCM_PLD_TDI        
                                  F6       JTAG_SCM_PLD_TDO        
                                  F7       PVCCA_AUX_PLD           
                                  F8       RST_WDTRST_PLD_R2_N     
                                  F9       BMC_CPLD_GPIO_22_R2     
                                  F10      BMC_CPLD_GPIO_24_R2     
                                  F11      P3V3_AUX                
                                  F12      BMC_CPLD_GPIO_20_R2     
                                  F13      BMC_CPLD_GPIO_18_R2     
                                  G1       JTAG_SCM_PLD_TMS        
                                  G2       JTAG_SCM_PLD_TCK        
                                  G3       P3V3_AUX                
                                  G4       PWRGD_PCH_PWROK         
                                  G5       BMC_CPLD_GPIO_2_R2      
                                  G6       PVCCA_AUX_PLD           
                                  G7       GND                     
                                  G8       PVCCA_AUX_PLD           
                                  G9       BMC_CPLD_GPIO_16_R2     
                                  G10      BMC_CPLD_GPIO_17_R2     
                                  G11      P3V3_AUX                
                                  G12      FM_BMC_ONCTL_R_N        
                                  G13      FM_BMC_EN_DET_R         
                                  H1       RST_PCA9548_SENSOR_N    
                                  H2       IRQ_UV_DETECT_N         
                                  H3       RST_BMC_RSTBTN_OUT_N    
                                  H4       FM_PCH_BMC_THERMTRIP_N  
                                  H5       FM_BIOS_POST_CMPLT_BMC_N
                                  H6       CLK_25M_OSC_FPGA        
                                  H7       PVCCA_AUX_PLD           
                                  H8       FM_PCHHOT_R_N           
                                  H9       FM_MASTER_MB_N          
                                  H10      RST_MB_STBY_R_N         
                                  H11      P3V3_AUX                
                                  H12      GND                     
                                  H13      FM_ADR_TRIGGER_N        
                                  J1       FM_ME_BT_DONE           
                                  J2       FM_PCIE_M2_SSD0_PRSNT_N 
                                  J3       P3V3_AUX                
                                  J4       GND                     
                                  J5       FM_CPU_MSMI_CATERR_LVT3_PLD_N
                                  J6       FM_ADR_COMPLETE         
                                  J7       SGPIO_PLD_LD_0          
                                  J8       BMC_CPLD_GPIO_9_R2      
                                  J9       FM_PMBUS_ALERT_EN       
                                  J10      BMC_CPLD_GPIO_15_R2     
                                  J11      P3V3_AUX                
                                  J12      FM_ESPI_PLD_R_EN        
                                  J13      H_CPU0_PROCHOT_LVC1_R_N 
                                  K1       SMB_BMC_ALERT10_R1_N    
                                  K2       RST_SRST_PLD_BMC_R_N    
                                  K3       P3V3_AUX                
                                  K4       PVCCD_PLL_AUX           
                                  K5       BMC_CPLD_GPIO_6_R2      
                                  K6       SGPIO_CLK_PLD_0         
                                  K7       FM_THERMTRIP_DLY_LVC1_R_N
                                  K8       BMC_CPLD_GPIO_10_R2     
                                  K9       PVCCD_PLL_AUX           
                                  K10      BMC_CPLD_GPIO_13_R2     
                                  K11      BMC_CPLD_GPIO_14_R2     
                                  K12      FM_SLPS3_GF_R_N         
                                  K13      FM_THROTTLE_R_N         
                                  L1       FM_PECI_SEL_N           
                                  L2       SMB_BMC_ALERT4_R1_N     
                                  L3       BMC_CPLD_GPIO_3_R2      
                                  L4       BMC_CPLD_GPIO_4_R2      
                                  L5       FM_MB_STBY_R_EN         
                                  L6       P3V3_AUX                
                                  L7       P3V3_AUX                
                                  L8       P3V3_AUX                
                                  L9       GND                     
                                  L10      BMC_CPLD_GPIO_12_R2     
                                  L11      BMC_CPLD_GPIO_8_R2      
                                  L12      RST_BMC_SELF_HW_R2      
                                  L13      RST_ROT_CPU_R_N         
                                  M1       IRQ_BMC_PCH_NMI_R_N     
                                  M2       H_CPU1_PROCHOT_LVC1_R_N 
                                  M3       SMB_BMC_ALERT9_R1_N     
                                  M4       IRQ_PCH_SCI_WHEA_R_N    
                                  M5       BMC_CPLD_GPIO_5_R2      
                                  M6       GND                     
                                  M7       IRQ_CPU1_VRHOT_N        
                                  M8       IRQ_OC_DETECT_EN_N      
                                  M9       SGPIO_PLD_DO_0          
                                  M10      BMC_CPLD_GPIO_11_R2     
                                  M11      BMC_CPLD_GPIO_7_R2      
                                  M12      IRQ_SGPIO_R_N           
                                  M13      FM_SPD_REMOTE_EN_R      
                                  N1       GND                     
                                  N2       VOL_SEN_ALERT_R         
                                  N3       SMB_BMC_ALERT3_R1_N     
                                  N4       PWR_BTN_BMC_N           
                                  N5       RST_EXTRST_R_N          
                                  N6       PWRGD_CPUPWRGD_LVC1     
                                  N7       IRQ_CPU0_VRHOT_N        
                                  N8       IRQ_OC_DETECT_N         
                                  N9       RST_SGPIO_RESET_R_N     
                                  N10      H_CPU1_MEMTRIP_LVC1_N   
                                  N11      SGPIO_PLD_DI_0          
                                  N12      H_CPU0_MEMTRIP_LVC1_N   
                                  N13      GND                     
U26              74HC1G126GW-74HC1G126GW,SMLF,IA 1        BMC_DDC_BUF_EN          
                                  2        V_VGAVS                 
                                  3        GND                     
                                  4        V_VGAVS_BUF_R           
                                  5        BMC_DDC_BUF_PWR         
U28              MX66L1G45GMI08G-MX66L1G45GMI-0A 1        SPI_BMC_IO3_FLASH_R2    
                                  2        P3V3_AUX                
                                  3        RST_SPI_BMC_FLASH_R2_N  
                                  7        SPI_BMC_CS1_FLASH_R2_N  
                                  8        SPI_BMC_IO1_FLASH_R2    
                                  9        SPI_BMC_IO2_FLASH_R2    
                                  10       GND                     
                                  15       SPI_BMC_IO0_FLASH_R2    
                                  16       SPI_BMC_CLK_FLASH_R2    
U29              74HC1G126GW-74HC1G126GW,SMLF,IA 1        DEBUG_PORT_PRSNT        
                                  2        SPA_SOUT_SW_DBG         
                                  3        GND                     
                                  4        DEBUG_PORT_UART_TX      
                                  5        P3V3_AUX                
U30              IDTQS3VH257PAG_SMLF-IDTQS3VH25A 1        FM_BMC_BIOS_MUX_CS_SPI_R_SEL_0
                                  2        SPI_SYS_MUX_MOSI        
                                  3        SPI_BMC_BIOS_ROM_R_MOSI 
                                  4        SPI_PCH_MUXED_IO0       
                                  5        SPI_SYS_MUX_HOLD_IO3    
                                  6        SPI_BMC_BIOS_ROM_R_IO3  
                                  7        SPI_PCH_MUXED_IO3       
                                  8        GND                     
                                  9        SPI_PCH_MUXED_CLK       
                                  10       SPI_BMC_BIOS_ROM_R_CLK  
                                  11       SPI_SYS_MUX_CLK         
                                  15       PD_BIOS_MUX_EN_N        
                                  16       P3V3_AUX                
U31              74LVC1G07GW-74LVC1G07GW,SMLF,IA 2        REAR_PWR_BTN_N          
                                  3        GND                     
                                  4        PWR_BTN_BMC_N           
                                  5        P3V3_AUX                
U32              74LVC1G17GW-74LVC1G17GW,SMLF,IA 2        REAR_ID_RST_BTN_N       
                                  3        GND                     
                                  4        ID_RST_BTN_BMC_N        
                                  5        P3V3_AUX                
U33              74HC1G126GW-74HC1G126GW,SMLF,IA 1        BMC_DDC_BUF_EN          
                                  2        V_VGAHS                 
                                  3        GND                     
                                  4        V_VGAHS_BUF_R           
                                  5        BMC_DDC_BUF_PWR         
U34              TPD4E001DBVR-TPD4E001DBVR,SMLFA 1        V_BMC_LS_DDC_SDA_R      
                                  2        GND                     
                                  3        V_BMC_LS_DDC_SCL_R      
                                  4        V_VGAVS_BUF             
                                  5        CRT_VCC5                
                                  6        V_VGAHS_BUF             
U35              TPD4E001DBVR-TPD4E001DBVR,SMLFA 1        V_DACB_IO               
                                  2        GND                     
                                  3        V_DACG_IO               
                                  4        V_DACR_IO               
                                  5        CRT_VCC5                
U36              74HC1G126GW-74HC1G126GW,SMLF,IA 1        DEBUG_PORT_PRSNT        
                                  2        DEBUG_PORT_UART_RX      
                                  3        GND                     
                                  4        SPA_SIN_SW_DBG          
                                  5        P3V3_AUX                
U38              PRTR5V0U2X-PRTR5V0U2X,SMLF,IC,A 1        GND                     
                                  2        USB2_01_F_DP            
                                  3        USB2_01_F_DN            
                                  4        P5V_USB_REAR            
U43              TPS3808G33DBVR-TPS3808G33DBVR,A 1        PWRGD_P1V0_AUX_DELAY_R1 
                                  2        GND                     
                                  3        PWRGD_P1V0_AUX_R2       
                                  4        U43_CT                  
                                  5        P1V0_AUX                
                                  6        P3V3_AUX                
Y1               Q_XTAL_4P_13BI_24GND-25MHZ,SMLA 1        XTAL_PHY_XI_R           
                                  2        GND                     
                                  3        XTAL_PHY_XO_R           
                                  4        GND                     
END BODY ORDERED NET LIST
